(kicad_sch
	(version 20231120)
	(generator "eeschema")
	(generator_version "8.0")
	(paper "A3")
	(title_block
		(title "Jetson Orin Baseboard")
		(date "2025-03-12")
		(rev "1.3.4")
		(company "Antmicro Ltd")
		(comment 1 "www.antmicro.com")
	)
	(junction
		(at 344.17 29.21)
		(diameter 0)
		(color 0 0 0 0)
	)
	(junction
		(at 349.25 29.21)
		(diameter 0)
		(color 0 0 0 0)
	)
	(junction
		(at 359.41 29.21)
		(diameter 0)
		(color 0 0 0 0)
	)
	(junction
		(at 295.91 25.4)
		(diameter 0)
		(color 0 0 0 0)
	)
	(junction
		(at 52.07 104.14)
		(diameter 0)
		(color 0 0 0 0)
	)
	(junction
		(at 242.57 203.2)
		(diameter 0)
		(color 0 0 0 0)
	)
	(junction
		(at 243.84 151.13)
		(diameter 0)
		(color 0 0 0 0)
	)
	(junction
		(at 379.73 29.21)
		(diameter 0)
		(color 0 0 0 0)
	)
	(junction
		(at 184.15 162.56)
		(diameter 0)
		(color 0 0 0 0)
	)
	(junction
		(at 369.57 29.21)
		(diameter 0)
		(color 0 0 0 0)
	)
	(junction
		(at 295.91 33.02)
		(diameter 0)
		(color 0 0 0 0)
	)
	(junction
		(at 344.17 110.49)
		(diameter 0)
		(color 0 0 0 0)
	)
	(junction
		(at 177.8 69.85)
		(diameter 0)
		(color 0 0 0 0)
	)
	(junction
		(at 175.26 152.4)
		(diameter 0)
		(color 0 0 0 0)
	)
	(junction
		(at 40.64 154.94)
		(diameter 0)
		(color 0 0 0 0)
	)
	(junction
		(at 175.26 160.02)
		(diameter 0)
		(color 0 0 0 0)
	)
	(junction
		(at 255.27 151.13)
		(diameter 0)
		(color 0 0 0 0)
	)
	(junction
		(at 46.99 154.94)
		(diameter 0)
		(color 0 0 0 0)
	)
	(junction
		(at 147.32 69.85)
		(diameter 0)
		(color 0 0 0 0)
	)
	(junction
		(at 223.52 266.7)
		(diameter 0)
		(color 0 0 0 0)
	)
	(junction
		(at 304.8 35.56)
		(diameter 0)
		(color 0 0 0 0)
	)
	(no_connect
		(at 191.77 259.08)
	)
	(no_connect
		(at 191.77 261.62)
	)
	(no_connect
		(at 191.77 264.16)
	)
	(no_connect
		(at 191.77 246.38)
	)
	(no_connect
		(at 191.77 248.92)
	)
	(no_connect
		(at 191.77 251.46)
	)
	(no_connect
		(at 191.77 254)
	)
	(no_connect
		(at 191.77 256.54)
	)
	(no_connect
		(at 222.25 223.52)
	)
	(no_connect
		(at 222.25 226.06)
	)
	(no_connect
		(at 222.25 228.6)
	)
	(no_connect
		(at 222.25 234.95)
	)
	(no_connect
		(at 222.25 240.03)
	)
	(no_connect
		(at 222.25 237.49)
	)
	(no_connect
		(at 191.77 193.04)
	)
	(no_connect
		(at 191.77 195.58)
	)
	(no_connect
		(at 191.77 200.66)
	)
	(no_connect
		(at 191.77 203.2)
	)
	(no_connect
		(at 191.77 208.28)
	)
	(no_connect
		(at 191.77 210.82)
	)
	(no_connect
		(at 191.77 215.9)
	)
	(no_connect
		(at 191.77 218.44)
	)
	(no_connect
		(at 191.77 220.98)
	)
	(wire
		(pts
			(xy 241.3 224.79) (xy 241.3 227.33)
		)
		(stroke
			(width 0)
			(type default)
		)
	)
	(wire
		(pts
			(xy 40.64 34.29) (xy 64.77 34.29)
		)
		(stroke
			(width 0)
			(type default)
		)
	)
	(wire
		(pts
			(xy 307.34 214.63) (xy 320.04 214.63)
		)
		(stroke
			(width 0)
			(type default)
		)
	)
	(wire
		(pts
			(xy 344.17 110.49) (xy 344.17 107.95)
		)
		(stroke
			(width 0)
			(type default)
		)
	)
	(wire
		(pts
			(xy 304.8 25.4) (xy 295.91 25.4)
		)
		(stroke
			(width 0)
			(type default)
		)
	)
	(wire
		(pts
			(xy 177.8 86.36) (xy 165.1 86.36)
		)
		(stroke
			(width 0)
			(type default)
		)
	)
	(wire
		(pts
			(xy 295.91 33.02) (xy 312.42 33.02)
		)
		(stroke
			(width 0)
			(type default)
		)
	)
	(wire
		(pts
			(xy 255.27 157.48) (xy 255.27 158.75)
		)
		(stroke
			(width 0)
			(type default)
		)
	)
	(wire
		(pts
			(xy 165.1 92.71) (xy 203.2 92.71)
		)
		(stroke
			(width 0)
			(type default)
		)
	)
	(wire
		(pts
			(xy 46.99 160.02) (xy 46.99 162.56)
		)
		(stroke
			(width 0)
			(type default)
		)
	)
	(wire
		(pts
			(xy 312.42 57.15) (xy 285.75 57.15)
		)
		(stroke
			(width 0)
			(type default)
		)
	)
	(wire
		(pts
			(xy 344.17 33.02) (xy 344.17 29.21)
		)
		(stroke
			(width 0)
			(type default)
		)
	)
	(wire
		(pts
			(xy 184.15 162.56) (xy 191.77 162.56)
		)
		(stroke
			(width 0)
			(type default)
		)
	)
	(wire
		(pts
			(xy 148.59 160.02) (xy 175.26 160.02)
		)
		(stroke
			(width 0)
			(type default)
		)
	)
	(wire
		(pts
			(xy 243.84 151.13) (xy 243.84 152.4)
		)
		(stroke
			(width 0)
			(type default)
		)
	)
	(wire
		(pts
			(xy 312.42 54.61) (xy 281.94 54.61)
		)
		(stroke
			(width 0)
			(type default)
		)
	)
	(wire
		(pts
			(xy 177.8 57.15) (xy 177.8 69.85)
		)
		(stroke
			(width 0)
			(type default)
		)
	)
	(wire
		(pts
			(xy 148.59 177.8) (xy 157.48 177.8)
		)
		(stroke
			(width 0)
			(type default)
		)
	)
	(wire
		(pts
			(xy 142.24 50.8) (xy 152.4 50.8)
		)
		(stroke
			(width 0)
			(type default)
		)
	)
	(wire
		(pts
			(xy 396.24 121.92) (xy 397.51 121.92)
		)
		(stroke
			(width 0)
			(type default)
		)
	)
	(wire
		(pts
			(xy 48.26 157.48) (xy 46.99 157.48)
		)
		(stroke
			(width 0)
			(type default)
		)
	)
	(wire
		(pts
			(xy 130.81 91.44) (xy 130.81 92.71)
		)
		(stroke
			(width 0)
			(type default)
		)
	)
	(wire
		(pts
			(xy 52.07 99.06) (xy 52.07 104.14)
		)
		(stroke
			(width 0)
			(type default)
		)
	)
	(wire
		(pts
			(xy 259.08 149.86) (xy 259.08 151.13)
		)
		(stroke
			(width 0)
			(type default)
		)
	)
	(wire
		(pts
			(xy 242.57 203.2) (xy 264.16 203.2)
		)
		(stroke
			(width 0)
			(type default)
		)
	)
	(wire
		(pts
			(xy 52.07 104.14) (xy 41.91 104.14)
		)
		(stroke
			(width 0)
			(type default)
		)
	)
	(wire
		(pts
			(xy 167.64 233.68) (xy 171.45 233.68)
		)
		(stroke
			(width 0)
			(type default)
		)
	)
	(wire
		(pts
			(xy 342.9 59.69) (xy 359.41 59.69)
		)
		(stroke
			(width 0)
			(type default)
		)
	)
	(wire
		(pts
			(xy 223.52 267.97) (xy 223.52 266.7)
		)
		(stroke
			(width 0)
			(type default)
		)
	)
	(wire
		(pts
			(xy 254 224.79) (xy 254 227.33)
		)
		(stroke
			(width 0)
			(type default)
		)
	)
	(wire
		(pts
			(xy 222.25 187.96) (xy 246.38 187.96)
		)
		(stroke
			(width 0)
			(type default)
		)
	)
	(wire
		(pts
			(xy 254 250.19) (xy 222.25 250.19)
		)
		(stroke
			(width 0)
			(type default)
		)
	)
	(wire
		(pts
			(xy 269.24 87.63) (xy 281.94 87.63)
		)
		(stroke
			(width 0)
			(type default)
		)
	)
	(wire
		(pts
			(xy 165.1 96.52) (xy 166.37 96.52)
		)
		(stroke
			(width 0)
			(type default)
		)
	)
	(wire
		(pts
			(xy 162.56 177.8) (xy 191.77 177.8)
		)
		(stroke
			(width 0)
			(type default)
		)
	)
	(wire
		(pts
			(xy 69.85 39.37) (xy 101.6 39.37)
		)
		(stroke
			(width 0)
			(type default)
		)
	)
	(wire
		(pts
			(xy 142.24 46.99) (xy 152.4 46.99)
		)
		(stroke
			(width 0)
			(type default)
		)
	)
	(wire
		(pts
			(xy 379.73 29.21) (xy 379.73 30.48)
		)
		(stroke
			(width 0)
			(type default)
		)
	)
	(wire
		(pts
			(xy 312.42 102.87) (xy 285.75 102.87)
		)
		(stroke
			(width 0)
			(type default)
		)
	)
	(wire
		(pts
			(xy 191.77 172.72) (xy 148.59 172.72)
		)
		(stroke
			(width 0)
			(type default)
		)
	)
	(wire
		(pts
			(xy 222.25 213.36) (xy 238.76 213.36)
		)
		(stroke
			(width 0)
			(type default)
		)
	)
	(wire
		(pts
			(xy 255.27 200.66) (xy 276.86 200.66)
		)
		(stroke
			(width 0)
			(type default)
		)
	)
	(wire
		(pts
			(xy 342.9 33.02) (xy 344.17 33.02)
		)
		(stroke
			(width 0)
			(type default)
		)
	)
	(wire
		(pts
			(xy 147.32 86.36) (xy 152.4 86.36)
		)
		(stroke
			(width 0)
			(type default)
		)
	)
	(wire
		(pts
			(xy 312.42 110.49) (xy 269.24 110.49)
		)
		(stroke
			(width 0)
			(type default)
		)
	)
	(wire
		(pts
			(xy 62.23 99.06) (xy 52.07 99.06)
		)
		(stroke
			(width 0)
			(type default)
		)
	)
	(wire
		(pts
			(xy 173.99 233.68) (xy 191.77 233.68)
		)
		(stroke
			(width 0)
			(type default)
		)
	)
	(wire
		(pts
			(xy 130.81 97.79) (xy 130.81 99.06)
		)
		(stroke
			(width 0)
			(type default)
		)
	)
	(wire
		(pts
			(xy 175.26 158.75) (xy 175.26 160.02)
		)
		(stroke
			(width 0)
			(type default)
		)
	)
	(wire
		(pts
			(xy 255.27 151.13) (xy 255.27 152.4)
		)
		(stroke
			(width 0)
			(type default)
		)
	)
	(polyline
		(pts
			(xy 19.05 26.67) (xy 106.68 26.67)
		)
		(stroke
			(width 0)
			(type default)
		)
	)
	(polyline
		(pts
			(xy 106.68 26.67) (xy 106.68 52.07)
		)
		(stroke
			(width 0)
			(type default)
		)
	)
	(wire
		(pts
			(xy 52.07 104.14) (xy 62.23 104.14)
		)
		(stroke
			(width 0)
			(type default)
		)
	)
	(wire
		(pts
			(xy 168.91 80.01) (xy 168.91 82.55)
		)
		(stroke
			(width 0)
			(type default)
		)
	)
	(wire
		(pts
			(xy 222.25 205.74) (xy 237.49 205.74)
		)
		(stroke
			(width 0)
			(type default)
		)
	)
	(wire
		(pts
			(xy 397.51 121.92) (xy 397.51 123.19)
		)
		(stroke
			(width 0)
			(type default)
		)
	)
	(polyline
		(pts
			(xy 114.3 31.75) (xy 204.47 31.75)
		)
		(stroke
			(width 0)
			(type default)
		)
	)
	(polyline
		(pts
			(xy 19.05 52.07) (xy 106.68 52.07)
		)
		(stroke
			(width 0)
			(type default)
		)
	)
	(wire
		(pts
			(xy 276.86 214.63) (xy 297.18 214.63)
		)
		(stroke
			(width 0)
			(type default)
		)
	)
	(wire
		(pts
			(xy 223.52 264.16) (xy 223.52 266.7)
		)
		(stroke
			(width 0)
			(type default)
		)
	)
	(wire
		(pts
			(xy 203.2 69.85) (xy 177.8 69.85)
		)
		(stroke
			(width 0)
			(type default)
		)
	)
	(wire
		(pts
			(xy 191.77 187.96) (xy 148.59 187.96)
		)
		(stroke
			(width 0)
			(type default)
		)
	)
	(wire
		(pts
			(xy 254 232.41) (xy 254 234.95)
		)
		(stroke
			(width 0)
			(type default)
		)
	)
	(polyline
		(pts
			(xy 114.3 130.81) (xy 114.3 31.75)
		)
		(stroke
			(width 0)
			(type default)
		)
	)
	(wire
		(pts
			(xy 307.34 209.55) (xy 320.04 209.55)
		)
		(stroke
			(width 0)
			(type default)
		)
	)
	(wire
		(pts
			(xy 121.92 62.23) (xy 142.24 62.23)
		)
		(stroke
			(width 0)
			(type default)
		)
	)
	(wire
		(pts
			(xy 307.34 207.01) (xy 320.04 207.01)
		)
		(stroke
			(width 0)
			(type default)
		)
	)
	(wire
		(pts
			(xy 269.24 69.85) (xy 276.86 69.85)
		)
		(stroke
			(width 0)
			(type default)
		)
	)
	(wire
		(pts
			(xy 295.91 31.75) (xy 295.91 33.02)
		)
		(stroke
			(width 0)
			(type default)
		)
	)
	(wire
		(pts
			(xy 222.25 190.5) (xy 246.38 190.5)
		)
		(stroke
			(width 0)
			(type default)
		)
	)
	(wire
		(pts
			(xy 175.26 160.02) (xy 191.77 160.02)
		)
		(stroke
			(width 0)
			(type default)
		)
	)
	(wire
		(pts
			(xy 276.86 212.09) (xy 297.18 212.09)
		)
		(stroke
			(width 0)
			(type default)
		)
	)
	(wire
		(pts
			(xy 151.13 60.96) (xy 151.13 63.5)
		)
		(stroke
			(width 0)
			(type default)
		)
	)
	(wire
		(pts
			(xy 269.24 100.33) (xy 276.86 100.33)
		)
		(stroke
			(width 0)
			(type default)
		)
	)
	(wire
		(pts
			(xy 153.67 231.14) (xy 157.48 231.14)
		)
		(stroke
			(width 0)
			(type default)
		)
	)
	(polyline
		(pts
			(xy 106.68 132.08) (xy 106.68 177.8)
		)
		(stroke
			(width 0)
			(type default)
		)
	)
	(wire
		(pts
			(xy 243.84 157.48) (xy 243.84 158.75)
		)
		(stroke
			(width 0)
			(type default)
		)
	)
	(wire
		(pts
			(xy 130.81 45.72) (xy 130.81 43.18)
		)
		(stroke
			(width 0)
			(type default)
		)
	)
	(wire
		(pts
			(xy 369.57 29.21) (xy 359.41 29.21)
		)
		(stroke
			(width 0)
			(type default)
		)
	)
	(wire
		(pts
			(xy 222.25 185.42) (xy 264.16 185.42)
		)
		(stroke
			(width 0)
			(type default)
		)
	)
	(wire
		(pts
			(xy 342.9 45.72) (xy 358.14 45.72)
		)
		(stroke
			(width 0)
			(type default)
		)
	)
	(wire
		(pts
			(xy 58.42 39.37) (xy 64.77 39.37)
		)
		(stroke
			(width 0)
			(type default)
		)
	)
	(wire
		(pts
			(xy 254 35.56) (xy 304.8 35.56)
		)
		(stroke
			(width 0)
			(type default)
		)
	)
	(wire
		(pts
			(xy 342.9 87.63) (xy 344.17 87.63)
		)
		(stroke
			(width 0)
			(type default)
		)
	)
	(wire
		(pts
			(xy 142.24 62.23) (xy 142.24 50.8)
		)
		(stroke
			(width 0)
			(type default)
		)
	)
	(wire
		(pts
			(xy 312.42 69.85) (xy 281.94 69.85)
		)
		(stroke
			(width 0)
			(type default)
		)
	)
	(wire
		(pts
			(xy 342.9 62.23) (xy 359.41 62.23)
		)
		(stroke
			(width 0)
			(type default)
		)
	)
	(wire
		(pts
			(xy 184.15 152.4) (xy 184.15 153.67)
		)
		(stroke
			(width 0)
			(type default)
		)
	)
	(wire
		(pts
			(xy 312.42 80.01) (xy 269.24 80.01)
		)
		(stroke
			(width 0)
			(type default)
		)
	)
	(wire
		(pts
			(xy 304.8 35.56) (xy 312.42 35.56)
		)
		(stroke
			(width 0)
			(type default)
		)
	)
	(wire
		(pts
			(xy 312.42 77.47) (xy 269.24 77.47)
		)
		(stroke
			(width 0)
			(type default)
		)
	)
	(wire
		(pts
			(xy 255.27 151.13) (xy 243.84 151.13)
		)
		(stroke
			(width 0)
			(type default)
		)
	)
	(wire
		(pts
			(xy 269.24 102.87) (xy 280.67 102.87)
		)
		(stroke
			(width 0)
			(type default)
		)
	)
	(wire
		(pts
			(xy 82.55 154.94) (xy 67.31 154.94)
		)
		(stroke
			(width 0)
			(type default)
		)
	)
	(wire
		(pts
			(xy 295.91 25.4) (xy 295.91 26.67)
		)
		(stroke
			(width 0)
			(type default)
		)
	)
	(wire
		(pts
			(xy 359.41 29.21) (xy 359.41 30.48)
		)
		(stroke
			(width 0)
			(type default)
		)
	)
	(wire
		(pts
			(xy 369.57 29.21) (xy 369.57 30.48)
		)
		(stroke
			(width 0)
			(type default)
		)
	)
	(wire
		(pts
			(xy 379.73 25.4) (xy 379.73 29.21)
		)
		(stroke
			(width 0)
			(type default)
		)
	)
	(wire
		(pts
			(xy 165.1 57.15) (xy 177.8 57.15)
		)
		(stroke
			(width 0)
			(type default)
		)
	)
	(wire
		(pts
			(xy 153.67 233.68) (xy 157.48 233.68)
		)
		(stroke
			(width 0)
			(type default)
		)
	)
	(wire
		(pts
			(xy 226.06 151.13) (xy 226.06 160.02)
		)
		(stroke
			(width 0)
			(type default)
		)
	)
	(wire
		(pts
			(xy 276.86 199.39) (xy 276.86 200.66)
		)
		(stroke
			(width 0)
			(type default)
		)
	)
	(wire
		(pts
			(xy 151.13 162.56) (xy 184.15 162.56)
		)
		(stroke
			(width 0)
			(type default)
		)
	)
	(wire
		(pts
			(xy 40.64 46.99) (xy 64.77 46.99)
		)
		(stroke
			(width 0)
			(type default)
		)
	)
	(wire
		(pts
			(xy 153.67 226.06) (xy 157.48 226.06)
		)
		(stroke
			(width 0)
			(type default)
		)
	)
	(wire
		(pts
			(xy 123.19 43.18) (xy 130.81 43.18)
		)
		(stroke
			(width 0)
			(type default)
		)
	)
	(wire
		(pts
			(xy 276.86 209.55) (xy 297.18 209.55)
		)
		(stroke
			(width 0)
			(type default)
		)
	)
	(wire
		(pts
			(xy 349.25 29.21) (xy 349.25 30.48)
		)
		(stroke
			(width 0)
			(type default)
		)
	)
	(wire
		(pts
			(xy 165.1 82.55) (xy 168.91 82.55)
		)
		(stroke
			(width 0)
			(type default)
		)
	)
	(wire
		(pts
			(xy 222.25 264.16) (xy 223.52 264.16)
		)
		(stroke
			(width 0)
			(type default)
		)
	)
	(polyline
		(pts
			(xy 19.05 52.07) (xy 19.05 26.67)
		)
		(stroke
			(width 0)
			(type default)
		)
	)
	(wire
		(pts
			(xy 342.9 64.77) (xy 359.41 64.77)
		)
		(stroke
			(width 0)
			(type default)
		)
	)
	(wire
		(pts
			(xy 342.9 110.49) (xy 344.17 110.49)
		)
		(stroke
			(width 0)
			(type default)
		)
	)
	(wire
		(pts
			(xy 40.64 154.94) (xy 46.99 154.94)
		)
		(stroke
			(width 0)
			(type default)
		)
	)
	(wire
		(pts
			(xy 147.32 57.15) (xy 147.32 69.85)
		)
		(stroke
			(width 0)
			(type default)
		)
	)
	(wire
		(pts
			(xy 153.67 228.6) (xy 157.48 228.6)
		)
		(stroke
			(width 0)
			(type default)
		)
	)
	(wire
		(pts
			(xy 48.26 160.02) (xy 46.99 160.02)
		)
		(stroke
			(width 0)
			(type default)
		)
	)
	(wire
		(pts
			(xy 269.24 57.15) (xy 280.67 57.15)
		)
		(stroke
			(width 0)
			(type default)
		)
	)
	(wire
		(pts
			(xy 222.25 203.2) (xy 242.57 203.2)
		)
		(stroke
			(width 0)
			(type default)
		)
	)
	(wire
		(pts
			(xy 52.07 104.14) (xy 52.07 109.22)
		)
		(stroke
			(width 0)
			(type default)
		)
	)
	(wire
		(pts
			(xy 269.24 85.09) (xy 278.13 85.09)
		)
		(stroke
			(width 0)
			(type default)
		)
	)
	(wire
		(pts
			(xy 312.42 62.23) (xy 269.24 62.23)
		)
		(stroke
			(width 0)
			(type default)
		)
	)
	(wire
		(pts
			(xy 251.46 172.72) (xy 270.51 172.72)
		)
		(stroke
			(width 0)
			(type default)
		)
	)
	(wire
		(pts
			(xy 284.48 275.59) (xy 285.75 275.59)
		)
		(stroke
			(width 0)
			(type default)
		)
	)
	(wire
		(pts
			(xy 359.41 29.21) (xy 349.25 29.21)
		)
		(stroke
			(width 0)
			(type default)
		)
	)
	(wire
		(pts
			(xy 142.24 92.71) (xy 152.4 92.71)
		)
		(stroke
			(width 0)
			(type default)
		)
	)
	(polyline
		(pts
			(xy 12.7 132.08) (xy 406.4 132.08)
		)
		(stroke
			(width 0)
			(type default)
		)
	)
	(wire
		(pts
			(xy 69.85 36.83) (xy 101.6 36.83)
		)
		(stroke
			(width 0)
			(type default)
		)
	)
	(wire
		(pts
			(xy 222.25 245.11) (xy 241.3 245.11)
		)
		(stroke
			(width 0)
			(type default)
		)
	)
	(wire
		(pts
			(xy 147.32 57.15) (xy 152.4 57.15)
		)
		(stroke
			(width 0)
			(type default)
		)
	)
	(wire
		(pts
			(xy 175.26 151.13) (xy 175.26 152.4)
		)
		(stroke
			(width 0)
			(type default)
		)
	)
	(wire
		(pts
			(xy 147.32 69.85) (xy 139.7 69.85)
		)
		(stroke
			(width 0)
			(type default)
		)
	)
	(wire
		(pts
			(xy 242.57 200.66) (xy 250.19 200.66)
		)
		(stroke
			(width 0)
			(type default)
		)
	)
	(wire
		(pts
			(xy 165.1 50.8) (xy 203.2 50.8)
		)
		(stroke
			(width 0)
			(type default)
		)
	)
	(wire
		(pts
			(xy 312.42 87.63) (xy 287.02 87.63)
		)
		(stroke
			(width 0)
			(type default)
		)
	)
	(wire
		(pts
			(xy 276.86 207.01) (xy 297.18 207.01)
		)
		(stroke
			(width 0)
			(type default)
		)
	)
	(wire
		(pts
			(xy 281.94 100.33) (xy 312.42 100.33)
		)
		(stroke
			(width 0)
			(type default)
		)
	)
	(wire
		(pts
			(xy 295.91 24.13) (xy 295.91 25.4)
		)
		(stroke
			(width 0)
			(type default)
		)
	)
	(wire
		(pts
			(xy 222.25 198.12) (xy 264.16 198.12)
		)
		(stroke
			(width 0)
			(type default)
		)
	)
	(wire
		(pts
			(xy 344.17 85.09) (xy 344.17 87.63)
		)
		(stroke
			(width 0)
			(type default)
		)
	)
	(wire
		(pts
			(xy 67.31 109.22) (xy 74.93 109.22)
		)
		(stroke
			(width 0)
			(type default)
		)
	)
	(wire
		(pts
			(xy 344.17 29.21) (xy 349.25 29.21)
		)
		(stroke
			(width 0)
			(type default)
		)
	)
	(wire
		(pts
			(xy 379.73 29.21) (xy 369.57 29.21)
		)
		(stroke
			(width 0)
			(type default)
		)
	)
	(wire
		(pts
			(xy 312.42 64.77) (xy 269.24 64.77)
		)
		(stroke
			(width 0)
			(type default)
		)
	)
	(wire
		(pts
			(xy 255.27 151.13) (xy 259.08 151.13)
		)
		(stroke
			(width 0)
			(type default)
		)
	)
	(wire
		(pts
			(xy 58.42 36.83) (xy 64.77 36.83)
		)
		(stroke
			(width 0)
			(type default)
		)
	)
	(wire
		(pts
			(xy 191.77 185.42) (xy 148.59 185.42)
		)
		(stroke
			(width 0)
			(type default)
		)
	)
	(wire
		(pts
			(xy 344.17 27.94) (xy 344.17 29.21)
		)
		(stroke
			(width 0)
			(type default)
		)
	)
	(wire
		(pts
			(xy 222.25 160.02) (xy 226.06 160.02)
		)
		(stroke
			(width 0)
			(type default)
		)
	)
	(polyline
		(pts
			(xy 106.68 76.2) (xy 106.68 132.08)
		)
		(stroke
			(width 0)
			(type default)
		)
	)
	(wire
		(pts
			(xy 285.75 275.59) (xy 285.75 276.86)
		)
		(stroke
			(width 0)
			(type default)
		)
	)
	(wire
		(pts
			(xy 166.37 96.52) (xy 166.37 99.06)
		)
		(stroke
			(width 0)
			(type default)
		)
	)
	(wire
		(pts
			(xy 175.26 152.4) (xy 175.26 153.67)
		)
		(stroke
			(width 0)
			(type default)
		)
	)
	(wire
		(pts
			(xy 344.17 77.47) (xy 344.17 80.01)
		)
		(stroke
			(width 0)
			(type default)
		)
	)
	(wire
		(pts
			(xy 344.17 71.12) (xy 344.17 72.39)
		)
		(stroke
			(width 0)
			(type default)
		)
	)
	(polyline
		(pts
			(xy 12.7 76.2) (xy 106.68 76.2)
		)
		(stroke
			(width 0)
			(type default)
		)
	)
	(wire
		(pts
			(xy 167.64 226.06) (xy 191.77 226.06)
		)
		(stroke
			(width 0)
			(type default)
		)
	)
	(wire
		(pts
			(xy 269.24 54.61) (xy 276.86 54.61)
		)
		(stroke
			(width 0)
			(type default)
		)
	)
	(wire
		(pts
			(xy 251.46 190.5) (xy 264.16 190.5)
		)
		(stroke
			(width 0)
			(type default)
		)
	)
	(wire
		(pts
			(xy 67.31 99.06) (xy 91.44 99.06)
		)
		(stroke
			(width 0)
			(type default)
		)
	)
	(wire
		(pts
			(xy 167.64 228.6) (xy 191.77 228.6)
		)
		(stroke
			(width 0)
			(type default)
		)
	)
	(wire
		(pts
			(xy 254 38.1) (xy 312.42 38.1)
		)
		(stroke
			(width 0)
			(type default)
		)
	)
	(wire
		(pts
			(xy 304.8 25.4) (xy 304.8 26.67)
		)
		(stroke
			(width 0)
			(type default)
		)
	)
	(wire
		(pts
			(xy 152.4 165.1) (xy 191.77 165.1)
		)
		(stroke
			(width 0)
			(type default)
		)
	)
	(wire
		(pts
			(xy 173.99 241.3) (xy 191.77 241.3)
		)
		(stroke
			(width 0)
			(type default)
		)
	)
	(wire
		(pts
			(xy 304.8 31.75) (xy 304.8 35.56)
		)
		(stroke
			(width 0)
			(type default)
		)
	)
	(wire
		(pts
			(xy 177.8 69.85) (xy 177.8 86.36)
		)
		(stroke
			(width 0)
			(type default)
		)
	)
	(wire
		(pts
			(xy 153.67 238.76) (xy 168.91 238.76)
		)
		(stroke
			(width 0)
			(type default)
		)
	)
	(wire
		(pts
			(xy 222.25 208.28) (xy 237.49 208.28)
		)
		(stroke
			(width 0)
			(type default)
		)
	)
	(wire
		(pts
			(xy 307.34 212.09) (xy 320.04 212.09)
		)
		(stroke
			(width 0)
			(type default)
		)
	)
	(wire
		(pts
			(xy 69.85 46.99) (xy 101.6 46.99)
		)
		(stroke
			(width 0)
			(type default)
		)
	)
	(polyline
		(pts
			(xy 210.82 12.7) (xy 210.82 132.08)
		)
		(stroke
			(width 0)
			(type default)
		)
	)
	(wire
		(pts
			(xy 241.3 240.03) (xy 241.3 245.11)
		)
		(stroke
			(width 0)
			(type default)
		)
	)
	(wire
		(pts
			(xy 241.3 232.41) (xy 241.3 234.95)
		)
		(stroke
			(width 0)
			(type default)
		)
	)
	(wire
		(pts
			(xy 191.77 170.18) (xy 148.59 170.18)
		)
		(stroke
			(width 0)
			(type default)
		)
	)
	(wire
		(pts
			(xy 191.77 180.34) (xy 166.37 180.34)
		)
		(stroke
			(width 0)
			(type default)
		)
	)
	(wire
		(pts
			(xy 222.25 172.72) (xy 246.38 172.72)
		)
		(stroke
			(width 0)
			(type default)
		)
	)
	(wire
		(pts
			(xy 153.67 241.3) (xy 168.91 241.3)
		)
		(stroke
			(width 0)
			(type default)
		)
	)
	(wire
		(pts
			(xy 312.42 48.26) (xy 269.24 48.26)
		)
		(stroke
			(width 0)
			(type default)
		)
	)
	(polyline
		(pts
			(xy 12.7 177.8) (xy 106.68 177.8)
		)
		(stroke
			(width 0)
			(type default)
		)
	)
	(wire
		(pts
			(xy 344.17 107.95) (xy 342.9 107.95)
		)
		(stroke
			(width 0)
			(type default)
		)
	)
	(wire
		(pts
			(xy 251.46 187.96) (xy 264.16 187.96)
		)
		(stroke
			(width 0)
			(type default)
		)
	)
	(wire
		(pts
			(xy 191.77 231.14) (xy 173.99 231.14)
		)
		(stroke
			(width 0)
			(type default)
		)
	)
	(wire
		(pts
			(xy 139.7 77.47) (xy 142.24 77.47)
		)
		(stroke
			(width 0)
			(type default)
		)
	)
	(wire
		(pts
			(xy 142.24 77.47) (xy 142.24 92.71)
		)
		(stroke
			(width 0)
			(type default)
		)
	)
	(wire
		(pts
			(xy 312.42 85.09) (xy 283.21 85.09)
		)
		(stroke
			(width 0)
			(type default)
		)
	)
	(wire
		(pts
			(xy 344.17 111.76) (xy 344.17 110.49)
		)
		(stroke
			(width 0)
			(type default)
		)
	)
	(wire
		(pts
			(xy 379.73 19.05) (xy 379.73 20.32)
		)
		(stroke
			(width 0)
			(type default)
		)
	)
	(wire
		(pts
			(xy 184.15 158.75) (xy 184.15 162.56)
		)
		(stroke
			(width 0)
			(type default)
		)
	)
	(wire
		(pts
			(xy 52.07 109.22) (xy 62.23 109.22)
		)
		(stroke
			(width 0)
			(type default)
		)
	)
	(wire
		(pts
			(xy 147.32 86.36) (xy 147.32 69.85)
		)
		(stroke
			(width 0)
			(type default)
		)
	)
	(wire
		(pts
			(xy 312.42 95.25) (xy 269.24 95.25)
		)
		(stroke
			(width 0)
			(type default)
		)
	)
	(wire
		(pts
			(xy 184.15 152.4) (xy 175.26 152.4)
		)
		(stroke
			(width 0)
			(type default)
		)
	)
	(wire
		(pts
			(xy 312.42 45.72) (xy 269.24 45.72)
		)
		(stroke
			(width 0)
			(type default)
		)
	)
	(wire
		(pts
			(xy 46.99 157.48) (xy 46.99 154.94)
		)
		(stroke
			(width 0)
			(type default)
		)
	)
	(wire
		(pts
			(xy 254 240.03) (xy 254 250.19)
		)
		(stroke
			(width 0)
			(type default)
		)
	)
	(wire
		(pts
			(xy 226.06 151.13) (xy 243.84 151.13)
		)
		(stroke
			(width 0)
			(type default)
		)
	)
	(wire
		(pts
			(xy 222.25 195.58) (xy 264.16 195.58)
		)
		(stroke
			(width 0)
			(type default)
		)
	)
	(wire
		(pts
			(xy 167.64 231.14) (xy 171.45 231.14)
		)
		(stroke
			(width 0)
			(type default)
		)
	)
	(wire
		(pts
			(xy 151.13 60.96) (xy 152.4 60.96)
		)
		(stroke
			(width 0)
			(type default)
		)
	)
	(wire
		(pts
			(xy 173.99 231.14) (xy 171.45 233.68)
		)
		(stroke
			(width 0)
			(type default)
		)
	)
	(wire
		(pts
			(xy 173.99 238.76) (xy 191.77 238.76)
		)
		(stroke
			(width 0)
			(type default)
		)
	)
	(wire
		(pts
			(xy 40.64 154.94) (xy 40.64 153.67)
		)
		(stroke
			(width 0)
			(type default)
		)
	)
	(wire
		(pts
			(xy 312.42 92.71) (xy 269.24 92.71)
		)
		(stroke
			(width 0)
			(type default)
		)
	)
	(wire
		(pts
			(xy 46.99 154.94) (xy 48.26 154.94)
		)
		(stroke
			(width 0)
			(type default)
		)
	)
	(wire
		(pts
			(xy 269.24 72.39) (xy 280.67 72.39)
		)
		(stroke
			(width 0)
			(type default)
		)
	)
	(wire
		(pts
			(xy 171.45 231.14) (xy 173.99 233.68)
		)
		(stroke
			(width 0)
			(type default)
		)
	)
	(wire
		(pts
			(xy 223.52 266.7) (xy 222.25 266.7)
		)
		(stroke
			(width 0)
			(type default)
		)
	)
	(wire
		(pts
			(xy 312.42 107.95) (xy 269.24 107.95)
		)
		(stroke
			(width 0)
			(type default)
		)
	)
	(wire
		(pts
			(xy 312.42 72.39) (xy 285.75 72.39)
		)
		(stroke
			(width 0)
			(type default)
		)
	)
	(polyline
		(pts
			(xy 204.47 31.75) (xy 204.47 130.81)
		)
		(stroke
			(width 0)
			(type default)
		)
	)
	(wire
		(pts
			(xy 254 33.02) (xy 295.91 33.02)
		)
		(stroke
			(width 0)
			(type default)
		)
	)
	(wire
		(pts
			(xy 40.64 154.94) (xy 40.64 156.21)
		)
		(stroke
			(width 0)
			(type default)
		)
	)
	(wire
		(pts
			(xy 148.59 180.34) (xy 161.29 180.34)
		)
		(stroke
			(width 0)
			(type default)
		)
	)
	(wire
		(pts
			(xy 69.85 34.29) (xy 101.6 34.29)
		)
		(stroke
			(width 0)
			(type default)
		)
	)
	(polyline
		(pts
			(xy 114.3 130.81) (xy 204.47 130.81)
		)
		(stroke
			(width 0)
			(type default)
		)
	)
	(wire
		(pts
			(xy 130.81 50.8) (xy 130.81 52.07)
		)
		(stroke
			(width 0)
			(type default)
		)
	)
	(wire
		(pts
			(xy 222.25 210.82) (xy 238.76 210.82)
		)
		(stroke
			(width 0)
			(type default)
		)
	)
	(wire
		(pts
			(xy 67.31 104.14) (xy 91.44 104.14)
		)
		(stroke
			(width 0)
			(type default)
		)
	)
	(wire
		(pts
			(xy 40.64 161.29) (xy 40.64 162.56)
		)
		(stroke
			(width 0)
			(type default)
		)
	)
	(wire
		(pts
			(xy 242.57 200.66) (xy 242.57 203.2)
		)
		(stroke
			(width 0)
			(type default)
		)
	)
	(text "PCIe1 1x1 key E"
		(exclude_from_sim no)
		(at 185.42 140.97 0)
		(effects
			(font
				(size 4 4)
				(thickness 0.8)
				(bold yes)
			)
			(justify left bottom)
		)
	)
	(text "NOTE about PCIe 0 role switching:\nFor details, refer to the PCIe section of \n\"Jeton Orin NX Series Product Design Guide\"\nhttps://developer.nvidia.com/jetson-orin-nx-series-design-guide"
		(exclude_from_sim no)
		(at 128.905 128.905 0)
		(effects
			(font
				(size 1.27 1.27)
			)
			(justify left bottom)
		)
	)
	(text "M.2 PCIE_WAKE selector"
		(exclude_from_sim no)
		(at 20.32 88.9 0)
		(effects
			(font
				(size 4 4)
				(thickness 0.8)
				(bold yes)
			)
			(justify left bottom)
		)
	)
	(text "PCIe0 1x4 key M"
		(exclude_from_sim no)
		(at 215.9 25.4 0)
		(effects
			(font
				(size 4 4)
				(thickness 0.8)
				(bold yes)
			)
			(justify left bottom)
		)
	)
	(text "NOTE:\nPlace bulk caps near \nto the M.2 power pads"
		(exclude_from_sim no)
		(at 351.79 26.67 0)
		(effects
			(font
				(size 1.27 1.27)
			)
			(justify left bottom)
		)
	)
	(text "BT"
		(exclude_from_sim no)
		(at 250.825 244.475 0)
		(effects
			(font
				(size 1.27 1.27)
			)
			(justify left bottom)
		)
	)
	(text "WLAN\n"
		(exclude_from_sim no)
		(at 234.315 244.475 0)
		(effects
			(font
				(size 1.27 1.27)
			)
			(justify left bottom)
		)
	)
	(text "NOTE:\nPlace bulk caps near \nto the M.2 power pads"
		(exclude_from_sim no)
		(at 234.95 149.86 0)
		(effects
			(font
				(size 1.27 1.27)
			)
			(justify left bottom)
		)
	)
	(text "NOTE:\nDNP for M.2 key M\nroot port role"
		(exclude_from_sim no)
		(at 114.935 38.735 0)
		(effects
			(font
				(size 1.27 1.27)
				(thickness 0.254)
				(bold yes)
			)
			(justify left bottom)
		)
	)
	(text "PCIe0 Root Port / Endpoint mode selector"
		(exclude_from_sim no)
		(at 45.72 25.4 0)
		(effects
			(font
				(size 4 4)
				(thickness 0.8)
				(bold yes)
			)
			(justify left bottom)
		)
	)
	(text "SUSCLK SOURCE"
		(exclude_from_sim no)
		(at 33.02 140.97 0)
		(effects
			(font
				(size 4 4)
				(thickness 0.8)
				(bold yes)
			)
			(justify left bottom)
		)
	)
	(text "NOTE:\nDNP for M.2 key M\nendpoint role"
		(exclude_from_sim no)
		(at 19.685 33.655 0)
		(effects
			(font
				(size 1.27 1.27)
				(thickness 0.254)
				(bold yes)
			)
			(justify left bottom)
		)
	)
	(label "M2_E_PCM_OUT"
		(at 173.99 231.14 0)
		(effects
			(font
				(size 1.27 1.27)
			)
			(justify left bottom)
		)
	)
	(label "3V3_M2"
		(at 360.68 29.21 0)
		(effects
			(font
				(size 1.27 1.27)
			)
			(justify left bottom)
		)
	)
	(label "M2_E_UART_CTS"
		(at 276.86 209.55 0)
		(effects
			(font
				(size 1.27 1.27)
			)
			(justify left bottom)
		)
	)
	(label "C_PCIE0_TX3_P"
		(at 308.61 100.33 180)
		(effects
			(font
				(size 1.524 1.524)
			)
			(justify right bottom)
		)
	)
	(label "M2_E_SUSCLK"
		(at 223.52 172.72 0)
		(effects
			(font
				(size 1.27 1.27)
			)
			(justify left bottom)
		)
	)
	(label "C_PCIE1_TX0_N"
		(at 171.45 180.34 0)
		(effects
			(font
				(size 1.524 1.524)
			)
			(justify left bottom)
		)
	)
	(label "C_PCIE0_TX2_N"
		(at 309.88 87.63 180)
		(effects
			(font
				(size 1.524 1.524)
			)
			(justify right bottom)
		)
	)
	(label "~{M2_M_ALERT}"
		(at 344.17 59.69 0)
		(effects
			(font
				(size 1.27 1.27)
			)
			(justify left bottom)
		)
	)
	(label "~{M2_M_PERST}"
		(at 101.6 39.37 180)
		(effects
			(font
				(size 1.27 1.27)
			)
			(justify right bottom)
		)
	)
	(label "~{M2_M_CLKREQ0}"
		(at 101.6 36.83 180)
		(effects
			(font
				(size 1.27 1.27)
			)
			(justify right bottom)
		)
	)
	(label "M2_M_SMB_DATA"
		(at 344.17 62.23 0)
		(effects
			(font
				(size 1.27 1.27)
			)
			(justify left bottom)
		)
	)
	(label "~{M2_M_CLKREQ0}"
		(at 254 35.56 0)
		(effects
			(font
				(size 1.27 1.27)
			)
			(justify left bottom)
		)
	)
	(label "~{M2_M_PEWAKE0}"
		(at 254 38.1 0)
		(effects
			(font
				(size 1.27 1.27)
			)
			(justify left bottom)
		)
	)
	(label "M2_E_I2C_CLK"
		(at 223.52 190.5 0)
		(effects
			(font
				(size 1.27 1.27)
			)
			(justify left bottom)
		)
	)
	(label "PCIE_WAKE_SEL0"
		(at 91.44 99.06 180)
		(effects
			(font
				(size 1.27 1.27)
			)
			(justify right bottom)
		)
	)
	(label "PCIE_WAKE_SEL1"
		(at 91.44 104.14 180)
		(effects
			(font
				(size 1.27 1.27)
			)
			(justify right bottom)
		)
	)
	(label "M2_E_UART_TX"
		(at 237.49 205.74 180)
		(effects
			(font
				(size 1.27 1.27)
			)
			(justify right bottom)
		)
	)
	(label "C_PCIE0_TX1_P"
		(at 309.88 69.85 180)
		(effects
			(font
				(size 1.524 1.524)
			)
			(justify right bottom)
		)
	)
	(label "M2_M_SMB_CLK"
		(at 344.17 64.77 0)
		(effects
			(font
				(size 1.27 1.27)
			)
			(justify left bottom)
		)
	)
	(label "C_PCIE1_TX0_P"
		(at 171.45 177.8 0)
		(effects
			(font
				(size 1.524 1.524)
			)
			(justify left bottom)
		)
	)
	(label "3V3_M2"
		(at 142.24 46.99 0)
		(effects
			(font
				(size 1.27 1.27)
			)
			(justify left bottom)
		)
	)
	(label "~{LED1}"
		(at 228.6 245.11 180)
		(effects
			(font
				(size 1.27 1.27)
			)
			(justify right bottom)
		)
	)
	(label "M2_E_UART_TX"
		(at 276.86 207.01 0)
		(effects
			(font
				(size 1.27 1.27)
			)
			(justify left bottom)
		)
	)
	(label "~{M2_M_PERST}"
		(at 203.2 92.71 180)
		(effects
			(font
				(size 1.27 1.27)
			)
			(justify right bottom)
		)
	)
	(label "M2_E_UART_RTS"
		(at 238.76 210.82 180)
		(effects
			(font
				(size 1.27 1.27)
			)
			(justify right bottom)
		)
	)
	(label "USB_E_P"
		(at 180.34 238.76 0)
		(effects
			(font
				(size 1.27 1.27)
			)
			(justify left bottom)
		)
	)
	(label "C_PCIE0_TX2_P"
		(at 309.88 85.09 180)
		(effects
			(font
				(size 1.524 1.524)
			)
			(justify right bottom)
		)
	)
	(label "~{M2_M_PEWAKE0}"
		(at 203.2 50.8 180)
		(effects
			(font
				(size 1.27 1.27)
			)
			(justify right bottom)
		)
	)
	(label "32.7KHZ_OUT"
		(at 40.64 46.99 0)
		(effects
			(font
				(size 1.27 1.27)
			)
			(justify left bottom)
		)
	)
	(label "C_PCIE0_TX0_N"
		(at 309.88 57.15 180)
		(effects
			(font
				(size 1.524 1.524)
			)
			(justify right bottom)
		)
	)
	(label "M2_E_UART_RX"
		(at 276.86 214.63 0)
		(effects
			(font
				(size 1.27 1.27)
			)
			(justify left bottom)
		)
	)
	(label "~{M2_M_CLKREQ0}"
		(at 203.2 69.85 180)
		(effects
			(font
				(size 1.27 1.27)
			)
			(justify right bottom)
		)
	)
	(label "32.7KHZ_OUT"
		(at 82.55 154.94 180)
		(effects
			(font
				(size 1.27 1.27)
			)
			(justify right bottom)
		)
	)
	(label "M2_E_UART_RX"
		(at 237.49 208.28 180)
		(effects
			(font
				(size 1.27 1.27)
			)
			(justify right bottom)
		)
	)
	(label "M2_E_PCM_SYNC"
		(at 173.99 228.6 0)
		(effects
			(font
				(size 1.27 1.27)
			)
			(justify left bottom)
		)
	)
	(label "M2_E_UART_RTS"
		(at 276.86 212.09 0)
		(effects
			(font
				(size 1.27 1.27)
			)
			(justify left bottom)
		)
	)
	(label "~{M2_E_ALERT}"
		(at 223.52 185.42 0)
		(effects
			(font
				(size 1.27 1.27)
			)
			(justify left bottom)
		)
	)
	(label "M2_E_W_DIS_1"
		(at 223.52 195.58 0)
		(effects
			(font
				(size 1.27 1.27)
			)
			(justify left bottom)
		)
	)
	(label "32.7KHZ_OUT"
		(at 270.51 172.72 180)
		(effects
			(font
				(size 1.27 1.27)
			)
			(justify right bottom)
		)
	)
	(label "3V3_M2"
		(at 123.19 43.18 0)
		(effects
			(font
				(size 1.27 1.27)
			)
			(justify left bottom)
		)
	)
	(label "M2_M_SUSCLK"
		(at 358.14 45.72 180)
		(effects
			(font
				(size 1.27 1.27)
			)
			(justify right bottom)
		)
	)
	(label "~{LED2}"
		(at 228.6 250.19 180)
		(effects
			(font
				(size 1.27 1.27)
			)
			(justify right bottom)
		)
	)
	(label "PCIE_WAKE_SEL0"
		(at 40.64 34.29 0)
		(effects
			(font
				(size 1.27 1.27)
			)
			(justify left bottom)
		)
	)
	(label "C_PCIE0_TX0_P"
		(at 309.88 54.61 180)
		(effects
			(font
				(size 1.524 1.524)
			)
			(justify right bottom)
		)
	)
	(label "~{M2_M_PERST}"
		(at 254 33.02 0)
		(effects
			(font
				(size 1.27 1.27)
			)
			(justify left bottom)
		)
	)
	(label "~{M2_M_PEWAKE0}"
		(at 101.6 34.29 180)
		(effects
			(font
				(size 1.27 1.27)
			)
			(justify right bottom)
		)
	)
	(label "C_PCIE0_TX1_N"
		(at 309.88 72.39 180)
		(effects
			(font
				(size 1.524 1.524)
			)
			(justify right bottom)
		)
	)
	(label "USB_E_N"
		(at 180.34 241.3 0)
		(effects
			(font
				(size 1.27 1.27)
			)
			(justify left bottom)
		)
	)
	(label "~{M2_E_UART_WAKE}"
		(at 223.52 203.2 0)
		(effects
			(font
				(size 1.27 1.27)
			)
			(justify left bottom)
		)
	)
	(label "M2_E_W_DIS_2"
		(at 223.52 198.12 0)
		(effects
			(font
				(size 1.27 1.27)
			)
			(justify left bottom)
		)
	)
	(label "PCIE_WAKE_SEL0"
		(at 121.92 62.23 0)
		(effects
			(font
				(size 1.27 1.27)
			)
			(justify left bottom)
		)
	)
	(label "C_PCIE0_TX3_N"
		(at 308.61 102.87 180)
		(effects
			(font
				(size 1.524 1.524)
			)
			(justify right bottom)
		)
	)
	(label "M2_E_UART_CTS"
		(at 238.76 213.36 180)
		(effects
			(font
				(size 1.27 1.27)
			)
			(justify right bottom)
		)
	)
	(label "M2_E_I2C_DAT"
		(at 223.52 187.96 0)
		(effects
			(font
				(size 1.27 1.27)
			)
			(justify left bottom)
		)
	)
	(label "M2_E_PCM_CLK"
		(at 173.99 226.06 0)
		(effects
			(font
				(size 1.27 1.27)
			)
			(justify left bottom)
		)
	)
	(label "PCIE_WAKE_SEL1"
		(at 152.4 165.1 0)
		(effects
			(font
				(size 1.27 1.27)
			)
			(justify left bottom)
		)
	)
	(label "M2_M_SUSCLK"
		(at 101.6 46.99 180)
		(effects
			(font
				(size 1.27 1.27)
			)
			(justify right bottom)
		)
	)
	(label "M2_E_PCM_IN"
		(at 173.99 233.68 0)
		(effects
			(font
				(size 1.27 1.27)
			)
			(justify left bottom)
		)
	)
	(global_label "PCIE0_RX0_P"
		(shape output)
		(at 269.24 62.23 180)
		(effects
			(font
				(size 1.27 1.27)
			)
			(justify right)
		)
		(property "Intersheetrefs" "${INTERSHEET_REFS}"
			(at 248.285 62.23 0)
			(effects
				(font
					(size 1.27 1.27)
				)
				(justify left)
			)
		)
	)
	(global_label "PCIE1_RX0_P"
		(shape output)
		(at 148.59 185.42 180)
		(effects
			(font
				(size 1.27 1.27)
			)
			(justify right)
		)
		(property "Intersheetrefs" "${INTERSHEET_REFS}"
			(at 127.635 185.42 0)
			(effects
				(font
					(size 1.27 1.27)
				)
				(justify left)
			)
		)
	)
	(global_label "PCIE0_RX3_N"
		(shape output)
		(at 269.24 110.49 180)
		(effects
			(font
				(size 1.27 1.27)
			)
			(justify right)
		)
		(property "Intersheetrefs" "${INTERSHEET_REFS}"
			(at 248.285 110.49 0)
			(effects
				(font
					(size 1.27 1.27)
				)
				(justify left)
			)
		)
	)
	(global_label "PCIE0_CLKREQ*"
		(shape output)
		(at 139.7 69.85 180)
		(effects
			(font
				(size 1.27 1.27)
			)
			(justify right)
		)
		(property "Intersheetrefs" "${INTERSHEET_REFS}"
			(at 120.65 69.85 0)
			(effects
				(font
					(size 1.27 1.27)
				)
				(justify right)
			)
		)
	)
	(global_label "PCIE0_TX2_N"
		(shape input)
		(at 269.24 87.63 180)
		(effects
			(font
				(size 1.27 1.27)
			)
			(justify right)
		)
		(property "Intersheetrefs" "${INTERSHEET_REFS}"
			(at 248.285 87.63 0)
			(effects
				(font
					(size 1.27 1.27)
				)
				(justify left)
			)
		)
	)
	(global_label "PCIE0_RX3_P"
		(shape output)
		(at 269.24 107.95 180)
		(effects
			(font
				(size 1.27 1.27)
			)
			(justify right)
		)
		(property "Intersheetrefs" "${INTERSHEET_REFS}"
			(at 248.285 107.95 0)
			(effects
				(font
					(size 1.27 1.27)
				)
				(justify left)
			)
		)
	)
	(global_label "PCIE0_TX3_N"
		(shape input)
		(at 269.24 102.87 180)
		(effects
			(font
				(size 1.27 1.27)
			)
			(justify right)
		)
		(property "Intersheetrefs" "${INTERSHEET_REFS}"
			(at 248.285 102.87 0)
			(effects
				(font
					(size 1.27 1.27)
				)
				(justify left)
			)
		)
	)
	(global_label "PCIE0_TX3_P"
		(shape input)
		(at 269.24 100.33 180)
		(effects
			(font
				(size 1.27 1.27)
			)
			(justify right)
		)
		(property "Intersheetrefs" "${INTERSHEET_REFS}"
			(at 248.285 100.33 0)
			(effects
				(font
					(size 1.27 1.27)
				)
				(justify left)
			)
		)
	)
	(global_label "PCIE0_RX1_N"
		(shape output)
		(at 269.24 80.01 180)
		(effects
			(font
				(size 1.27 1.27)
			)
			(justify right)
		)
		(property "Intersheetrefs" "${INTERSHEET_REFS}"
			(at 248.285 80.01 0)
			(effects
				(font
					(size 1.27 1.27)
				)
				(justify left)
			)
		)
	)
	(global_label "PCIE0_RX2_N"
		(shape output)
		(at 269.24 95.25 180)
		(effects
			(font
				(size 1.27 1.27)
			)
			(justify right)
		)
		(property "Intersheetrefs" "${INTERSHEET_REFS}"
			(at 248.285 95.25 0)
			(effects
				(font
					(size 1.27 1.27)
				)
				(justify left)
			)
		)
	)
	(global_label "PCIE0_RST*"
		(shape output)
		(at 139.7 77.47 180)
		(effects
			(font
				(size 1.27 1.27)
			)
			(justify right)
		)
		(property "Intersheetrefs" "${INTERSHEET_REFS}"
			(at 120.65 77.47 0)
			(effects
				(font
					(size 1.27 1.27)
				)
				(justify right)
			)
		)
	)
	(global_label "PCIE0_RX0_N"
		(shape output)
		(at 269.24 64.77 180)
		(effects
			(font
				(size 1.27 1.27)
			)
			(justify right)
		)
		(property "Intersheetrefs" "${INTERSHEET_REFS}"
			(at 248.285 64.77 0)
			(effects
				(font
					(size 1.27 1.27)
				)
				(justify left)
			)
		)
	)
	(global_label "I2S1_SCLK"
		(shape output)
		(at 153.67 226.06 180)
		(effects
			(font
				(size 1.27 1.27)
			)
			(justify right)
		)
		(property "Intersheetrefs" "${INTERSHEET_REFS}"
			(at 139.7 226.06 0)
			(effects
				(font
					(size 1.27 1.27)
				)
				(justify right)
			)
		)
	)
	(global_label "PCIE1_CLKREQ*"
		(shape output)
		(at 151.13 162.56 180)
		(effects
			(font
				(size 1.27 1.27)
			)
			(justify right)
		)
		(property "Intersheetrefs" "${INTERSHEET_REFS}"
			(at 132.08 162.56 0)
			(effects
				(font
					(size 1.27 1.27)
				)
				(justify right)
			)
		)
	)
	(global_label "PCIE0_CLKREQ*"
		(shape input)
		(at 58.42 36.83 180)
		(effects
			(font
				(size 1.27 1.27)
			)
			(justify right)
		)
		(property "Intersheetrefs" "${INTERSHEET_REFS}"
			(at 39.37 36.83 0)
			(effects
				(font
					(size 1.27 1.27)
				)
				(justify right)
			)
		)
	)
	(global_label "PCIE_WAKE_SEL_EXT"
		(shape input)
		(at 74.93 109.22 0)
		(effects
			(font
				(size 1.27 1.27)
			)
			(justify left)
		)
		(property "Intersheetrefs" "${INTERSHEET_REFS}"
			(at 97.79 109.22 0)
			(effects
				(font
					(size 1.27 1.27)
				)
				(justify left)
			)
		)
	)
	(global_label "PCIE0_RX1_P"
		(shape output)
		(at 269.24 77.47 180)
		(effects
			(font
				(size 1.27 1.27)
			)
			(justify right)
		)
		(property "Intersheetrefs" "${INTERSHEET_REFS}"
			(at 248.285 77.47 0)
			(effects
				(font
					(size 1.27 1.27)
				)
				(justify left)
			)
		)
	)
	(global_label "USB1_D_P"
		(shape input)
		(at 153.67 238.76 180)
		(effects
			(font
				(size 1.27 1.27)
			)
			(justify right)
		)
		(property "Intersheetrefs" "${INTERSHEET_REFS}"
			(at 137.795 238.76 0)
			(effects
				(font
					(size 1.27 1.27)
				)
				(justify right)
			)
		)
	)
	(global_label "PCIE0_RX2_P"
		(shape output)
		(at 269.24 92.71 180)
		(effects
			(font
				(size 1.27 1.27)
			)
			(justify right)
		)
		(property "Intersheetrefs" "${INTERSHEET_REFS}"
			(at 248.285 92.71 0)
			(effects
				(font
					(size 1.27 1.27)
				)
				(justify left)
			)
		)
	)
	(global_label "PCIE0_RST*"
		(shape input)
		(at 58.42 39.37 180)
		(effects
			(font
				(size 1.27 1.27)
			)
			(justify right)
		)
		(property "Intersheetrefs" "${INTERSHEET_REFS}"
			(at 39.37 39.37 0)
			(effects
				(font
					(size 1.27 1.27)
				)
				(justify right)
			)
		)
	)
	(global_label "PCIE_WAKE*"
		(shape output)
		(at 41.91 104.14 180)
		(effects
			(font
				(size 1.27 1.27)
			)
			(justify right)
		)
		(property "Intersheetrefs" "${INTERSHEET_REFS}"
			(at 26.67 104.14 0)
			(effects
				(font
					(size 1.27 1.27)
				)
				(justify right)
			)
		)
	)
	(global_label "I2S1_SDOUT"
		(shape output)
		(at 153.67 233.68 180)
		(effects
			(font
				(size 1.27 1.27)
			)
			(justify right)
		)
		(property "Intersheetrefs" "${INTERSHEET_REFS}"
			(at 139.7 233.68 0)
			(effects
				(font
					(size 1.27 1.27)
				)
				(justify right)
			)
		)
	)
	(global_label "PCIE0_CLK_N"
		(shape input)
		(at 269.24 48.26 180)
		(effects
			(font
				(size 1.27 1.27)
			)
			(justify right)
		)
		(property "Intersheetrefs" "${INTERSHEET_REFS}"
			(at 248.285 48.26 0)
			(effects
				(font
					(size 1.27 1.27)
				)
				(justify left)
			)
		)
	)
	(global_label "PCIE0_TX0_N"
		(shape input)
		(at 269.24 57.15 180)
		(effects
			(font
				(size 1.27 1.27)
			)
			(justify right)
		)
		(property "Intersheetrefs" "${INTERSHEET_REFS}"
			(at 248.285 57.15 0)
			(effects
				(font
					(size 1.27 1.27)
				)
				(justify left)
			)
		)
	)
	(global_label "PCIE0_CLK_P"
		(shape input)
		(at 269.24 45.72 180)
		(effects
			(font
				(size 1.27 1.27)
			)
			(justify right)
		)
		(property "Intersheetrefs" "${INTERSHEET_REFS}"
			(at 248.285 45.72 0)
			(effects
				(font
					(size 1.27 1.27)
				)
				(justify left)
			)
		)
	)
	(global_label "PCIE0_TX1_P"
		(shape input)
		(at 269.24 69.85 180)
		(effects
			(font
				(size 1.27 1.27)
			)
			(justify right)
		)
		(property "Intersheetrefs" "${INTERSHEET_REFS}"
			(at 248.285 69.85 0)
			(effects
				(font
					(size 1.27 1.27)
				)
				(justify left)
			)
		)
	)
	(global_label "PCIE1_RX0_N"
		(shape output)
		(at 148.59 187.96 180)
		(effects
			(font
				(size 1.27 1.27)
			)
			(justify right)
		)
		(property "Intersheetrefs" "${INTERSHEET_REFS}"
			(at 127.635 187.96 0)
			(effects
				(font
					(size 1.27 1.27)
				)
				(justify left)
			)
		)
	)
	(global_label "UART0_CTS"
		(shape output)
		(at 320.04 209.55 0)
		(effects
			(font
				(size 1.27 1.27)
			)
			(justify left)
		)
		(property "Intersheetrefs" "${INTERSHEET_REFS}"
			(at 334.01 209.55 0)
			(effects
				(font
					(size 1.27 1.27)
				)
				(justify left)
			)
		)
	)
	(global_label "PCIE1_TX0_P"
		(shape input)
		(at 148.59 177.8 180)
		(effects
			(font
				(size 1.27 1.27)
			)
			(justify right)
		)
		(property "Intersheetrefs" "${INTERSHEET_REFS}"
			(at 127.635 177.8 0)
			(effects
				(font
					(size 1.27 1.27)
				)
				(justify left)
			)
		)
	)
	(global_label "I2S1_SDIN"
		(shape input)
		(at 153.67 231.14 180)
		(effects
			(font
				(size 1.27 1.27)
			)
			(justify right)
		)
		(property "Intersheetrefs" "${INTERSHEET_REFS}"
			(at 139.7 231.14 0)
			(effects
				(font
					(size 1.27 1.27)
				)
				(justify right)
			)
		)
	)
	(global_label "PCIE0_TX0_P"
		(shape input)
		(at 269.24 54.61 180)
		(effects
			(font
				(size 1.27 1.27)
			)
			(justify right)
		)
		(property "Intersheetrefs" "${INTERSHEET_REFS}"
			(at 248.285 54.61 0)
			(effects
				(font
					(size 1.27 1.27)
				)
				(justify left)
			)
		)
	)
	(global_label "PCIE0_TX2_P"
		(shape input)
		(at 269.24 85.09 180)
		(effects
			(font
				(size 1.27 1.27)
			)
			(justify right)
		)
		(property "Intersheetrefs" "${INTERSHEET_REFS}"
			(at 248.285 85.09 0)
			(effects
				(font
					(size 1.27 1.27)
				)
				(justify left)
			)
		)
	)
	(global_label "USB1_D_N"
		(shape input)
		(at 153.67 241.3 180)
		(effects
			(font
				(size 1.27 1.27)
			)
			(justify right)
		)
		(property "Intersheetrefs" "${INTERSHEET_REFS}"
			(at 137.795 241.3 0)
			(effects
				(font
					(size 1.27 1.27)
				)
				(justify right)
			)
		)
	)
	(global_label "PCIE1_CLK_P"
		(shape input)
		(at 148.59 170.18 180)
		(effects
			(font
				(size 1.27 1.27)
			)
			(justify right)
		)
		(property "Intersheetrefs" "${INTERSHEET_REFS}"
			(at 132.08 170.18 0)
			(effects
				(font
					(size 1.27 1.27)
				)
				(justify right)
			)
		)
	)
	(global_label "UART0_RXD"
		(shape input)
		(at 320.04 214.63 0)
		(effects
			(font
				(size 1.27 1.27)
			)
			(justify left)
		)
		(property "Intersheetrefs" "${INTERSHEET_REFS}"
			(at 334.01 214.63 0)
			(effects
				(font
					(size 1.27 1.27)
				)
				(justify left)
			)
		)
	)
	(global_label "UART0_TXD"
		(shape output)
		(at 320.04 207.01 0)
		(effects
			(font
				(size 1.27 1.27)
			)
			(justify left)
		)
		(property "Intersheetrefs" "${INTERSHEET_REFS}"
			(at 334.01 207.01 0)
			(effects
				(font
					(size 1.27 1.27)
				)
				(justify left)
			)
		)
	)
	(global_label "PCIE0_TX1_N"
		(shape input)
		(at 269.24 72.39 180)
		(effects
			(font
				(size 1.27 1.27)
			)
			(justify right)
		)
		(property "Intersheetrefs" "${INTERSHEET_REFS}"
			(at 248.285 72.39 0)
			(effects
				(font
					(size 1.27 1.27)
				)
				(justify left)
			)
		)
	)
	(global_label "SYS_SCL"
		(shape input)
		(at 264.16 190.5 0)
		(effects
			(font
				(size 1.27 1.27)
			)
			(justify left)
		)
		(property "Intersheetrefs" "${INTERSHEET_REFS}"
			(at 276.86 190.5 0)
			(effects
				(font
					(size 1.27 1.27)
				)
				(justify left)
			)
		)
	)
	(global_label "PCIE1_CLK_N"
		(shape input)
		(at 148.59 172.72 180)
		(effects
			(font
				(size 1.27 1.27)
			)
			(justify right)
		)
		(property "Intersheetrefs" "${INTERSHEET_REFS}"
			(at 132.08 172.72 0)
			(effects
				(font
					(size 1.27 1.27)
				)
				(justify right)
			)
		)
	)
	(global_label "SYS_SDA"
		(shape bidirectional)
		(at 264.16 187.96 0)
		(effects
			(font
				(size 1.27 1.27)
			)
			(justify left)
		)
		(property "Intersheetrefs" "${INTERSHEET_REFS}"
			(at 276.86 187.96 0)
			(effects
				(font
					(size 1.27 1.27)
				)
				(justify left)
			)
		)
	)
	(global_label "I2S1_LRCK"
		(shape output)
		(at 153.67 228.6 180)
		(effects
			(font
				(size 1.27 1.27)
			)
			(justify right)
		)
		(property "Intersheetrefs" "${INTERSHEET_REFS}"
			(at 139.7 228.6 0)
			(effects
				(font
					(size 1.27 1.27)
				)
				(justify right)
			)
		)
	)
	(global_label "PCIE1_TX0_N"
		(shape input)
		(at 148.59 180.34 180)
		(effects
			(font
				(size 1.27 1.27)
			)
			(justify right)
		)
		(property "Intersheetrefs" "${INTERSHEET_REFS}"
			(at 127.635 180.34 0)
			(effects
				(font
					(size 1.27 1.27)
				)
				(justify left)
			)
		)
	)
	(global_label "PCIE1_RST*"
		(shape input)
		(at 148.59 160.02 180)
		(effects
			(font
				(size 1.27 1.27)
			)
			(justify right)
		)
		(property "Intersheetrefs" "${INTERSHEET_REFS}"
			(at 132.08 160.02 0)
			(effects
				(font
					(size 1.27 1.27)
				)
				(justify right)
			)
		)
	)
	(global_label "UART0_RTS"
		(shape input)
		(at 320.04 212.09 0)
		(effects
			(font
				(size 1.27 1.27)
			)
			(justify left)
		)
		(property "Intersheetrefs" "${INTERSHEET_REFS}"
			(at 334.01 212.09 0)
			(effects
				(font
					(size 1.27 1.27)
				)
				(justify left)
			)
		)
	)
	(symbol
		(lib_name "+3V3_3")
		(lib_id "antmicropower:+3V3")
		(at 379.73 19.05 0)
		(unit 1)
		(exclude_from_sim no)
		(in_bom yes)
		(on_board yes)
		(dnp no)
		(property "Reference" "#PWR041"
			(at 379.73 22.86 0)
			(effects
				(font
					(size 1.27 1.27)
				)
				(justify left bottom)
				(hide yes)
			)
		)
		(property "Value" "+3V3"
			(at 376.555 15.24 0)
			(effects
				(font
					(size 1.27 1.27)
					(thickness 0.15)
				)
				(justify left)
			)
		)
		(property "Footprint" ""
			(at 394.97 26.67 0)
			(effects
				(font
					(size 1.27 1.27)
					(thickness 0.15)
				)
				(justify left bottom)
				(hide yes)
			)
		)
		(property "Datasheet" ""
			(at 394.97 29.21 0)
			(effects
				(font
					(size 1.27 1.27)
					(thickness 0.15)
				)
				(justify left bottom)
				(hide yes)
			)
		)
		(property "Description" ""
			(at 379.73 19.05 0)
			(effects
				(font
					(size 1.27 1.27)
				)
				(hide yes)
			)
		)
		(property "Author" "Antmicro"
			(at 394.97 21.59 0)
			(effects
				(font
					(size 1.27 1.27)
					(thickness 0.15)
				)
				(justify left bottom)
				(hide yes)
			)
		)
		(property "License" "Apache-2.0"
			(at 394.97 24.13 0)
			(effects
				(font
					(size 1.27 1.27)
					(thickness 0.15)
				)
				(justify left bottom)
				(hide yes)
			)
		)
		(pin "1"
		)
		(instances
			(project "jetson-orin-baseboard"
				(path ""
					(reference "#PWR041")
					(unit 1)
				)
			)
		)
	)
	(symbol
		(lib_id "antmicroLogicBuffersDriversReceiversTransceivers:74LVC2G07_SOT457")
		(at 165.1 83.82 0)
		(mirror y)
		(unit 1)
		(exclude_from_sim no)
		(in_bom no)
		(on_board yes)
		(dnp yes)
		(property "Reference" "U3"
			(at 158.75 76.2 0)
			(effects
				(font
					(size 1.27 1.27)
				)
			)
		)
		(property "Value" "74LVC2G07_SOT457"
			(at 135.89 90.17 0)
			(effects
				(font
					(size 1.27 1.27)
					(thickness 0.15)
				)
				(justify left bottom)
				(hide yes)
			)
		)
		(property "Footprint" "antmicro-footprints:SC-74-6_1.5x2.9mm_P0.95mm"
			(at 135.89 92.71 0)
			(effects
				(font
					(size 1.27 1.27)
					(thickness 0.15)
				)
				(justify left bottom)
				(hide yes)
			)
		)
		(property "Datasheet" "https://www.tme.eu/Document/2ad9356043a4952b9021ef50162f8c34/74LVC2G07.pdf"
			(at 135.89 95.25 0)
			(effects
				(font
					(size 1.27 1.27)
					(thickness 0.15)
				)
				(justify left bottom)
				(hide yes)
			)
		)
		(property "Description" ""
			(at 165.1 83.82 0)
			(effects
				(font
					(size 1.27 1.27)
				)
				(hide yes)
			)
		)
		(property "Manufacturer" "Nexperia"
			(at 135.89 97.79 0)
			(effects
				(font
					(size 1.27 1.27)
					(thickness 0.15)
				)
				(justify left bottom)
				(hide yes)
			)
		)
		(property "MPN" "74LVC2G07GV,125"
			(at 158.75 78.74 0)
			(effects
				(font
					(size 1.27 1.27)
					(thickness 0.15)
				)
			)
		)
		(property "Author" "Antmicro"
			(at 135.89 102.87 0)
			(effects
				(font
					(size 1.27 1.27)
					(thickness 0.15)
				)
				(justify left bottom)
				(hide yes)
			)
		)
		(property "License" "Apache-2.0"
			(at 135.89 105.41 0)
			(effects
				(font
					(size 1.27 1.27)
					(thickness 0.15)
				)
				(justify left bottom)
				(hide yes)
			)
		)
		(pin "1"
		)
		(pin "2"
		)
		(pin "3"
		)
		(pin "4"
		)
		(pin "5"
		)
		(pin "6"
		)
		(instances
			(project "jetson-orin-baseboard"
				(path ""
					(reference "U3")
					(unit 1)
				)
			)
		)
	)
	(symbol
		(lib_id "antmicroOscillators:Oscillator_32.768kHz_ECS_2520MV")
		(at 48.26 154.94 0)
		(unit 1)
		(exclude_from_sim no)
		(in_bom yes)
		(on_board yes)
		(dnp no)
		(fields_autoplaced yes)
		(property "Reference" "Y1"
			(at 57.785 144.78 0)
			(effects
				(font
					(size 1.27 1.27)
					(thickness 0.15)
				)
			)
		)
		(property "Value" "Oscillator_32.768kHz_ECS_2520MV"
			(at 74.295 167.64 0)
			(effects
				(font
					(size 1.27 1.27)
					(thickness 0.15)
				)
				(justify left bottom)
				(hide yes)
			)
		)
		(property "Footprint" "antmicro-footprints:Oscillator_SMD_ECS_2520MV_2.5x2mm"
			(at 74.295 170.18 0)
			(effects
				(font
					(size 1.27 1.27)
					(thickness 0.15)
				)
				(justify left bottom)
				(hide yes)
			)
		)
		(property "Datasheet" "https://ecsxtal.com/store/pdf/ECS-327MVATX.pdf"
			(at 74.295 172.72 0)
			(effects
				(font
					(size 1.27 1.27)
					(thickness 0.15)
				)
				(justify left bottom)
				(hide yes)
			)
		)
		(property "Description" ""
			(at 48.26 154.94 0)
			(effects
				(font
					(size 1.27 1.27)
				)
				(hide yes)
			)
		)
		(property "Manufacturer" "ECS Inc. International"
			(at 74.295 162.56 0)
			(effects
				(font
					(size 1.27 1.27)
					(thickness 0.15)
				)
				(justify left bottom)
				(hide yes)
			)
		)
		(property "MPN" "ECS-327MVATX-2-CN-TR3"
			(at 57.785 147.32 0)
			(effects
				(font
					(size 1.27 1.27)
					(thickness 0.15)
				)
			)
		)
		(property "Val" "32.768 kHz"
			(at 57.785 149.86 0)
			(effects
				(font
					(size 1.27 1.27)
					(thickness 0.15)
				)
			)
		)
		(property "Author" "Antmicro"
			(at 74.295 175.26 0)
			(effects
				(font
					(size 1.27 1.27)
					(thickness 0.15)
				)
				(justify left bottom)
				(hide yes)
			)
		)
		(property "License" "Apache-2.0"
			(at 74.295 177.8 0)
			(effects
				(font
					(size 1.27 1.27)
					(thickness 0.15)
				)
				(justify left bottom)
				(hide yes)
			)
		)
		(pin "2"
		)
		(pin "1"
		)
		(pin "4"
		)
		(pin "3"
		)
		(instances
			(project "jetson-orin-baseboard"
				(path ""
					(reference "Y1")
					(unit 1)
				)
			)
		)
	)
	(symbol
		(lib_id "antmicroLEDIndicationDiscrete:LED_G_0603_LTST-C190GKT")
		(at 254 240.03 90)
		(unit 1)
		(exclude_from_sim no)
		(in_bom yes)
		(on_board yes)
		(dnp no)
		(fields_autoplaced yes)
		(property "Reference" "D52"
			(at 255.905 236.22 90)
			(effects
				(font
					(size 1.27 1.27)
				)
				(justify right)
			)
		)
		(property "Value" "LED_G_0603_LTST-C190GKT"
			(at 261.62 217.17 0)
			(effects
				(font
					(size 1.27 1.27)
					(thickness 0.15)
				)
				(justify left bottom)
				(hide yes)
			)
		)
		(property "Footprint" "antmicro-footprints:LED_0603_1608Metric_G"
			(at 264.16 217.17 0)
			(effects
				(font
					(size 1.27 1.27)
					(thickness 0.15)
				)
				(justify left bottom)
				(hide yes)
			)
		)
		(property "Datasheet" "https://media.digikey.com/pdf/Data%20Sheets/Lite-On%20PDFs/LTST-C190GKT.pdf"
			(at 266.7 217.17 0)
			(effects
				(font
					(size 1.27 1.27)
					(thickness 0.15)
				)
				(justify left bottom)
				(hide yes)
			)
		)
		(property "Description" ""
			(at 254 240.03 0)
			(effects
				(font
					(size 1.27 1.27)
				)
				(hide yes)
			)
		)
		(property "MPN" "LTST-C190GKT"
			(at 269.24 217.17 0)
			(effects
				(font
					(size 1.27 1.27)
					(thickness 0.15)
				)
				(justify left bottom)
				(hide yes)
			)
		)
		(property "Manufacturer" "Lite-On"
			(at 271.78 217.17 0)
			(effects
				(font
					(size 1.27 1.27)
					(thickness 0.15)
				)
				(justify left bottom)
				(hide yes)
			)
		)
		(property "Author" "Antmicro"
			(at 274.32 217.17 0)
			(effects
				(font
					(size 1.27 1.27)
					(thickness 0.15)
				)
				(justify left bottom)
				(hide yes)
			)
		)
		(property "License" "Apache-2.0"
			(at 276.86 217.17 0)
			(effects
				(font
					(size 1.27 1.27)
					(thickness 0.15)
				)
				(justify left bottom)
				(hide yes)
			)
		)
		(property "Color" "Green"
			(at 255.905 238.76 90)
			(effects
				(font
					(size 1.27 1.27)
				)
				(justify right)
			)
		)
		(pin "1"
		)
		(pin "2"
		)
		(instances
			(project "jetson-orin-baseboard"
				(path ""
					(reference "D52")
					(unit 1)
				)
			)
		)
	)
	(symbol
		(lib_name "R_47k_0402_1")
		(lib_id "antmicroResistors0402:R_47k_0402")
		(at 304.8 26.67 90)
		(mirror x)
		(unit 1)
		(exclude_from_sim no)
		(in_bom no)
		(on_board yes)
		(dnp yes)
		(property "Reference" "R38"
			(at 306.07 27.94 90)
			(effects
				(font
					(size 1.27 1.27)
				)
				(justify right)
			)
		)
		(property "Value" "R_47k_0402"
			(at 317.5 46.99 0)
			(effects
				(font
					(size 1.27 1.27)
					(thickness 0.15)
				)
				(justify left bottom)
				(hide yes)
			)
		)
		(property "Footprint" "antmicro-footprints:R_0402_1005Metric"
			(at 320.04 46.99 0)
			(effects
				(font
					(size 1.27 1.27)
					(thickness 0.15)
				)
				(justify left bottom)
				(hide yes)
			)
		)
		(property "Datasheet" "https://www.bourns.com/docs/product-datasheets/cr.pdf"
			(at 322.58 46.99 0)
			(effects
				(font
					(size 1.27 1.27)
					(thickness 0.15)
				)
				(justify left bottom)
				(hide yes)
			)
		)
		(property "Description" ""
			(at 304.8 26.67 0)
			(effects
				(font
					(size 1.27 1.27)
				)
				(hide yes)
			)
		)
		(property "Manufacturer" "Bourns"
			(at 327.66 46.99 0)
			(effects
				(font
					(size 1.27 1.27)
					(thickness 0.15)
				)
				(justify left bottom)
				(hide yes)
			)
		)
		(property "MPN" "CR0402-FX-4702GLF"
			(at 325.12 46.99 0)
			(effects
				(font
					(size 1.27 1.27)
					(thickness 0.15)
				)
				(justify left bottom)
				(hide yes)
			)
		)
		(property "Val" "47k"
			(at 306.07 30.48 90)
			(effects
				(font
					(size 1.27 1.27)
					(thickness 0.15)
				)
				(justify right)
			)
		)
		(property "License" "Apache-2.0"
			(at 330.2 46.99 0)
			(effects
				(font
					(size 1.27 1.27)
					(thickness 0.15)
				)
				(justify left bottom)
				(hide yes)
			)
		)
		(property "Author" "Antmicro"
			(at 332.74 46.99 0)
			(effects
				(font
					(size 1.27 1.27)
					(thickness 0.15)
				)
				(justify left bottom)
				(hide yes)
			)
		)
		(property "Tolerance" "1%"
			(at 314.96 46.99 0)
			(effects
				(font
					(size 1.27 1.27)
				)
				(justify left bottom)
				(hide yes)
			)
		)
		(pin "1"
		)
		(pin "2"
		)
		(instances
			(project "jetson-orin-baseboard"
				(path ""
					(reference "R38")
					(unit 1)
				)
			)
		)
	)
	(symbol
		(lib_id "antmicropower:+3V3")
		(at 276.86 199.39 0)
		(unit 1)
		(exclude_from_sim no)
		(in_bom yes)
		(on_board yes)
		(dnp no)
		(property "Reference" "#PWR033"
			(at 276.86 203.2 0)
			(effects
				(font
					(size 1.27 1.27)
				)
				(justify left bottom)
				(hide yes)
			)
		)
		(property "Value" "+3V3"
			(at 273.685 196.215 0)
			(effects
				(font
					(size 1.27 1.27)
					(thickness 0.15)
				)
				(justify left bottom)
			)
		)
		(property "Footprint" ""
			(at 292.1 207.01 0)
			(effects
				(font
					(size 1.27 1.27)
					(thickness 0.15)
				)
				(justify left bottom)
				(hide yes)
			)
		)
		(property "Datasheet" ""
			(at 292.1 209.55 0)
			(effects
				(font
					(size 1.27 1.27)
					(thickness 0.15)
				)
				(justify left bottom)
				(hide yes)
			)
		)
		(property "Description" ""
			(at 276.86 199.39 0)
			(effects
				(font
					(size 1.27 1.27)
				)
				(hide yes)
			)
		)
		(property "Author" "Antmicro"
			(at 292.1 201.93 0)
			(effects
				(font
					(size 1.27 1.27)
					(thickness 0.15)
				)
				(justify left bottom)
				(hide yes)
			)
		)
		(property "License" "Apache-2.0"
			(at 292.1 204.47 0)
			(effects
				(font
					(size 1.27 1.27)
					(thickness 0.15)
				)
				(justify left bottom)
				(hide yes)
			)
		)
		(pin "1"
		)
		(instances
			(project "jetson-orin-baseboard"
				(path ""
					(reference "#PWR033")
					(unit 1)
				)
			)
		)
	)
	(symbol
		(lib_id "antmicroResistors0402:R_0R_0402")
		(at 246.38 190.5 0)
		(unit 1)
		(exclude_from_sim no)
		(in_bom no)
		(on_board yes)
		(dnp yes)
		(property "Reference" "R31"
			(at 251.46 189.865 0)
			(effects
				(font
					(size 1.27 1.27)
				)
				(justify left bottom)
			)
		)
		(property "Value" "R_0R_0402"
			(at 266.7 203.2 0)
			(effects
				(font
					(size 1.27 1.27)
					(thickness 0.15)
				)
				(justify left bottom)
				(hide yes)
			)
		)
		(property "Footprint" "antmicro-footprints:R_0402_1005Metric"
			(at 266.7 205.74 0)
			(effects
				(font
					(size 1.27 1.27)
					(thickness 0.15)
				)
				(justify left bottom)
				(hide yes)
			)
		)
		(property "Datasheet" "https://industrial.panasonic.com/cdbs/www-data/pdf/RDA0000/AOA0000C301.pdf"
			(at 266.7 208.28 0)
			(effects
				(font
					(size 1.27 1.27)
					(thickness 0.15)
				)
				(justify left bottom)
				(hide yes)
			)
		)
		(property "Description" ""
			(at 246.38 190.5 0)
			(effects
				(font
					(size 1.27 1.27)
				)
				(hide yes)
			)
		)
		(property "Manufacturer" "Panasonic"
			(at 266.7 213.36 0)
			(effects
				(font
					(size 1.27 1.27)
					(thickness 0.15)
				)
				(justify left bottom)
				(hide yes)
			)
		)
		(property "MPN" "ERJ2GE0R00X"
			(at 266.7 210.82 0)
			(effects
				(font
					(size 1.27 1.27)
					(thickness 0.15)
				)
				(justify left bottom)
				(hide yes)
			)
		)
		(property "Val" "0R"
			(at 243.84 189.865 0)
			(effects
				(font
					(size 1.27 1.27)
					(thickness 0.15)
				)
				(justify left bottom)
			)
		)
		(property "License" "Apache-2.0"
			(at 266.7 215.9 0)
			(effects
				(font
					(size 1.27 1.27)
					(thickness 0.15)
				)
				(justify left bottom)
				(hide yes)
			)
		)
		(property "Author" "Antmicro"
			(at 266.7 218.44 0)
			(effects
				(font
					(size 1.27 1.27)
					(thickness 0.15)
				)
				(justify left bottom)
				(hide yes)
			)
		)
		(property "Tolerance" "~"
			(at 266.7 200.66 0)
			(effects
				(font
					(size 1.27 1.27)
				)
				(justify left bottom)
				(hide yes)
			)
		)
		(property "Current" "1A"
			(at 266.7 220.98 0)
			(effects
				(font
					(size 1.27 1.27)
					(thickness 0.15)
				)
				(justify left bottom)
				(hide yes)
			)
		)
		(pin "1"
		)
		(pin "2"
		)
		(instances
			(project "jetson-orin-baseboard"
				(path ""
					(reference "R31")
					(unit 1)
				)
			)
		)
	)
	(symbol
		(lib_id "antmicroCapacitors0603:C_10u_0603")
		(at 255.27 152.4 90)
		(mirror x)
		(unit 1)
		(exclude_from_sim no)
		(in_bom yes)
		(on_board yes)
		(dnp no)
		(fields_autoplaced yes)
		(property "Reference" "C12"
			(at 257.81 153.6763 90)
			(effects
				(font
					(size 1.27 1.27)
				)
				(justify right)
			)
		)
		(property "Value" "C_10u_0603"
			(at 265.43 172.72 0)
			(effects
				(font
					(size 1.27 1.27)
					(thickness 0.15)
				)
				(justify left bottom)
				(hide yes)
			)
		)
		(property "Footprint" "antmicro-footprints:C_0603_1608Metric"
			(at 267.97 172.72 0)
			(effects
				(font
					(size 1.27 1.27)
					(thickness 0.15)
				)
				(justify left bottom)
				(hide yes)
			)
		)
		(property "Datasheet" "https://www.murata.com/products/productdetail?partno=GRM188R61A106KE69%23"
			(at 270.51 172.72 0)
			(effects
				(font
					(size 1.27 1.27)
					(thickness 0.15)
				)
				(justify left bottom)
				(hide yes)
			)
		)
		(property "Description" ""
			(at 255.27 152.4 0)
			(effects
				(font
					(size 1.27 1.27)
				)
				(hide yes)
			)
		)
		(property "Manufacturer" "Murata"
			(at 275.59 172.72 0)
			(effects
				(font
					(size 1.27 1.27)
					(thickness 0.15)
				)
				(justify left bottom)
				(hide yes)
			)
		)
		(property "MPN" "GRM188R61A106KE69D"
			(at 273.05 172.72 0)
			(effects
				(font
					(size 1.27 1.27)
					(thickness 0.15)
				)
				(justify left bottom)
				(hide yes)
			)
		)
		(property "Val" "10u"
			(at 257.81 156.2163 90)
			(effects
				(font
					(size 1.27 1.27)
					(thickness 0.15)
				)
				(justify right)
			)
		)
		(property "License" "Apache-2.0"
			(at 278.13 172.72 0)
			(effects
				(font
					(size 1.27 1.27)
					(thickness 0.15)
				)
				(justify left bottom)
				(hide yes)
			)
		)
		(property "Author" "Antmicro"
			(at 280.67 172.72 0)
			(effects
				(font
					(size 1.27 1.27)
					(thickness 0.15)
				)
				(justify left bottom)
				(hide yes)
			)
		)
		(property "Voltage" ""
			(at 283.21 172.72 0)
			(effects
				(font
					(size 1.27 1.27)
				)
				(justify left bottom)
				(hide yes)
			)
		)
		(property "Dielectric" "template_dielectric"
			(at 285.75 172.72 0)
			(effects
				(font
					(size 1.27 1.27)
				)
				(justify left bottom)
				(hide yes)
			)
		)
		(pin "1"
		)
		(pin "2"
		)
		(instances
			(project "jetson-orin-baseboard"
				(path ""
					(reference "C12")
					(unit 1)
				)
			)
		)
	)
	(symbol
		(lib_id "antmicroResistors0402:R_0R_0402")
		(at 168.91 241.3 0)
		(unit 1)
		(exclude_from_sim no)
		(in_bom yes)
		(on_board yes)
		(dnp no)
		(property "Reference" "R52"
			(at 173.99 240.665 0)
			(effects
				(font
					(size 1.27 1.27)
				)
				(justify left bottom)
			)
		)
		(property "Value" "R_0R_0402"
			(at 189.23 254 0)
			(effects
				(font
					(size 1.27 1.27)
					(thickness 0.15)
				)
				(justify left bottom)
				(hide yes)
			)
		)
		(property "Footprint" "antmicro-footprints:R_0402_1005Metric"
			(at 189.23 256.54 0)
			(effects
				(font
					(size 1.27 1.27)
					(thickness 0.15)
				)
				(justify left bottom)
				(hide yes)
			)
		)
		(property "Datasheet" "https://industrial.panasonic.com/cdbs/www-data/pdf/RDA0000/AOA0000C301.pdf"
			(at 189.23 259.08 0)
			(effects
				(font
					(size 1.27 1.27)
					(thickness 0.15)
				)
				(justify left bottom)
				(hide yes)
			)
		)
		(property "Description" ""
			(at 168.91 241.3 0)
			(effects
				(font
					(size 1.27 1.27)
				)
				(hide yes)
			)
		)
		(property "Manufacturer" "Panasonic"
			(at 189.23 264.16 0)
			(effects
				(font
					(size 1.27 1.27)
					(thickness 0.15)
				)
				(justify left bottom)
				(hide yes)
			)
		)
		(property "MPN" "ERJ2GE0R00X"
			(at 189.23 261.62 0)
			(effects
				(font
					(size 1.27 1.27)
					(thickness 0.15)
				)
				(justify left bottom)
				(hide yes)
			)
		)
		(property "Val" "0R"
			(at 166.37 240.665 0)
			(effects
				(font
					(size 1.27 1.27)
					(thickness 0.15)
				)
				(justify left bottom)
			)
		)
		(property "License" "Apache-2.0"
			(at 189.23 266.7 0)
			(effects
				(font
					(size 1.27 1.27)
					(thickness 0.15)
				)
				(justify left bottom)
				(hide yes)
			)
		)
		(property "Author" "Antmicro"
			(at 189.23 269.24 0)
			(effects
				(font
					(size 1.27 1.27)
					(thickness 0.15)
				)
				(justify left bottom)
				(hide yes)
			)
		)
		(property "Tolerance" "~"
			(at 189.23 251.46 0)
			(effects
				(font
					(size 1.27 1.27)
				)
				(justify left bottom)
				(hide yes)
			)
		)
		(property "Current" "1A"
			(at 189.23 271.78 0)
			(effects
				(font
					(size 1.27 1.27)
					(thickness 0.15)
				)
				(justify left bottom)
				(hide yes)
			)
		)
		(pin "1"
		)
		(pin "2"
		)
		(instances
			(project "jetson-orin-baseboard"
				(path ""
					(reference "R52")
					(unit 1)
				)
			)
		)
	)
	(symbol
		(lib_id "antmicroCapacitors0603:C_10u_0603")
		(at 243.84 152.4 90)
		(mirror x)
		(unit 1)
		(exclude_from_sim no)
		(in_bom yes)
		(on_board yes)
		(dnp no)
		(fields_autoplaced yes)
		(property "Reference" "C11"
			(at 246.38 153.6763 90)
			(effects
				(font
					(size 1.27 1.27)
				)
				(justify right)
			)
		)
		(property "Value" "C_10u_0603"
			(at 254 172.72 0)
			(effects
				(font
					(size 1.27 1.27)
					(thickness 0.15)
				)
				(justify left bottom)
				(hide yes)
			)
		)
		(property "Footprint" "antmicro-footprints:C_0603_1608Metric"
			(at 256.54 172.72 0)
			(effects
				(font
					(size 1.27 1.27)
					(thickness 0.15)
				)
				(justify left bottom)
				(hide yes)
			)
		)
		(property "Datasheet" "https://www.murata.com/products/productdetail?partno=GRM188R61A106KE69%23"
			(at 259.08 172.72 0)
			(effects
				(font
					(size 1.27 1.27)
					(thickness 0.15)
				)
				(justify left bottom)
				(hide yes)
			)
		)
		(property "Description" ""
			(at 243.84 152.4 0)
			(effects
				(font
					(size 1.27 1.27)
				)
				(hide yes)
			)
		)
		(property "Manufacturer" "Murata"
			(at 264.16 172.72 0)
			(effects
				(font
					(size 1.27 1.27)
					(thickness 0.15)
				)
				(justify left bottom)
				(hide yes)
			)
		)
		(property "MPN" "GRM188R61A106KE69D"
			(at 261.62 172.72 0)
			(effects
				(font
					(size 1.27 1.27)
					(thickness 0.15)
				)
				(justify left bottom)
				(hide yes)
			)
		)
		(property "Val" "10u"
			(at 246.38 156.2163 90)
			(effects
				(font
					(size 1.27 1.27)
					(thickness 0.15)
				)
				(justify right)
			)
		)
		(property "License" "Apache-2.0"
			(at 266.7 172.72 0)
			(effects
				(font
					(size 1.27 1.27)
					(thickness 0.15)
				)
				(justify left bottom)
				(hide yes)
			)
		)
		(property "Author" "Antmicro"
			(at 269.24 172.72 0)
			(effects
				(font
					(size 1.27 1.27)
					(thickness 0.15)
				)
				(justify left bottom)
				(hide yes)
			)
		)
		(property "Voltage" ""
			(at 271.78 172.72 0)
			(effects
				(font
					(size 1.27 1.27)
				)
				(justify left bottom)
				(hide yes)
			)
		)
		(property "Dielectric" "template_dielectric"
			(at 274.32 172.72 0)
			(effects
				(font
					(size 1.27 1.27)
				)
				(justify left bottom)
				(hide yes)
			)
		)
		(pin "1"
		)
		(pin "2"
		)
		(instances
			(project "jetson-orin-baseboard"
				(path ""
					(reference "C11")
					(unit 1)
				)
			)
		)
	)
	(symbol
		(lib_name "C_220n_0402_1")
		(lib_id "antmicroCapacitors0402:C_220n_0402")
		(at 281.94 69.85 180)
		(unit 1)
		(exclude_from_sim no)
		(in_bom yes)
		(on_board yes)
		(dnp no)
		(property "Reference" "C14"
			(at 284.48 67.945 0)
			(effects
				(font
					(size 1.27 1.27)
				)
				(justify left bottom)
			)
		)
		(property "Value" "C_220n_0402"
			(at 261.62 59.69 0)
			(effects
				(font
					(size 1.27 1.27)
					(thickness 0.15)
				)
				(justify left bottom)
				(hide yes)
			)
		)
		(property "Footprint" "antmicro-footprints:C_0402_1005Metric"
			(at 261.62 57.15 0)
			(effects
				(font
					(size 1.27 1.27)
					(thickness 0.15)
				)
				(justify left bottom)
				(hide yes)
			)
		)
		(property "Datasheet" "https://www.yageo.com/en/Chart/Download/pdf/CC0402KRX5R6BB224"
			(at 261.62 54.61 0)
			(effects
				(font
					(size 1.27 1.27)
					(thickness 0.15)
				)
				(justify left bottom)
				(hide yes)
			)
		)
		(property "Description" ""
			(at 281.94 69.85 0)
			(effects
				(font
					(size 1.27 1.27)
				)
				(hide yes)
			)
		)
		(property "Manufacturer" "YAGEO"
			(at 261.62 49.53 0)
			(effects
				(font
					(size 1.27 1.27)
					(thickness 0.15)
				)
				(justify left bottom)
				(hide yes)
			)
		)
		(property "MPN" "CC0402KRX5R6BB224"
			(at 261.62 52.07 0)
			(effects
				(font
					(size 1.27 1.27)
					(thickness 0.15)
				)
				(justify left bottom)
				(hide yes)
			)
		)
		(property "Val" "220n"
			(at 278.13 70.485 0)
			(effects
				(font
					(size 1.27 1.27)
					(thickness 0.15)
				)
				(justify left bottom)
			)
		)
		(property "License" "Apache-2.0"
			(at 261.62 46.99 0)
			(effects
				(font
					(size 1.27 1.27)
					(thickness 0.15)
				)
				(justify left bottom)
				(hide yes)
			)
		)
		(property "Author" "Antmicro"
			(at 261.62 44.45 0)
			(effects
				(font
					(size 1.27 1.27)
					(thickness 0.15)
				)
				(justify left bottom)
				(hide yes)
			)
		)
		(property "Voltage" ""
			(at 261.62 41.91 0)
			(effects
				(font
					(size 1.27 1.27)
				)
				(justify left bottom)
				(hide yes)
			)
		)
		(property "Dielectric" ""
			(at 261.62 39.37 0)
			(effects
				(font
					(size 1.27 1.27)
				)
				(justify left bottom)
				(hide yes)
			)
		)
		(pin "1"
		)
		(pin "2"
		)
		(instances
			(project "jetson-orin-baseboard"
				(path ""
					(reference "C14")
					(unit 1)
				)
			)
		)
	)
	(symbol
		(lib_id "antmicroResistors0402:R_0R_0402")
		(at 246.38 187.96 0)
		(unit 1)
		(exclude_from_sim no)
		(in_bom no)
		(on_board yes)
		(dnp yes)
		(property "Reference" "R30"
			(at 251.46 187.325 0)
			(effects
				(font
					(size 1.27 1.27)
				)
				(justify left bottom)
			)
		)
		(property "Value" "R_0R_0402"
			(at 266.7 200.66 0)
			(effects
				(font
					(size 1.27 1.27)
					(thickness 0.15)
				)
				(justify left bottom)
				(hide yes)
			)
		)
		(property "Footprint" "antmicro-footprints:R_0402_1005Metric"
			(at 266.7 203.2 0)
			(effects
				(font
					(size 1.27 1.27)
					(thickness 0.15)
				)
				(justify left bottom)
				(hide yes)
			)
		)
		(property "Datasheet" "https://industrial.panasonic.com/cdbs/www-data/pdf/RDA0000/AOA0000C301.pdf"
			(at 266.7 205.74 0)
			(effects
				(font
					(size 1.27 1.27)
					(thickness 0.15)
				)
				(justify left bottom)
				(hide yes)
			)
		)
		(property "Description" ""
			(at 246.38 187.96 0)
			(effects
				(font
					(size 1.27 1.27)
				)
				(hide yes)
			)
		)
		(property "Manufacturer" "Panasonic"
			(at 266.7 210.82 0)
			(effects
				(font
					(size 1.27 1.27)
					(thickness 0.15)
				)
				(justify left bottom)
				(hide yes)
			)
		)
		(property "MPN" "ERJ2GE0R00X"
			(at 266.7 208.28 0)
			(effects
				(font
					(size 1.27 1.27)
					(thickness 0.15)
				)
				(justify left bottom)
				(hide yes)
			)
		)
		(property "Val" "0R"
			(at 243.84 187.325 0)
			(effects
				(font
					(size 1.27 1.27)
					(thickness 0.15)
				)
				(justify left bottom)
			)
		)
		(property "License" "Apache-2.0"
			(at 266.7 213.36 0)
			(effects
				(font
					(size 1.27 1.27)
					(thickness 0.15)
				)
				(justify left bottom)
				(hide yes)
			)
		)
		(property "Author" "Antmicro"
			(at 266.7 215.9 0)
			(effects
				(font
					(size 1.27 1.27)
					(thickness 0.15)
				)
				(justify left bottom)
				(hide yes)
			)
		)
		(property "Tolerance" "~"
			(at 266.7 198.12 0)
			(effects
				(font
					(size 1.27 1.27)
				)
				(justify left bottom)
				(hide yes)
			)
		)
		(property "Current" "1A"
			(at 266.7 218.44 0)
			(effects
				(font
					(size 1.27 1.27)
					(thickness 0.15)
				)
				(justify left bottom)
				(hide yes)
			)
		)
		(pin "1"
		)
		(pin "2"
		)
		(instances
			(project "jetson-orin-baseboard"
				(path ""
					(reference "R30")
					(unit 1)
				)
			)
		)
	)
	(symbol
		(lib_name "GND_2")
		(lib_id "antmicropower:GND")
		(at 151.13 63.5 0)
		(unit 1)
		(exclude_from_sim no)
		(in_bom yes)
		(on_board yes)
		(dnp no)
		(property "Reference" "#PWR024"
			(at 151.13 69.85 0)
			(effects
				(font
					(size 1.27 1.27)
				)
				(justify left bottom)
				(hide yes)
			)
		)
		(property "Value" "GND"
			(at 151.13 67.31 0)
			(effects
				(font
					(size 1.27 1.27)
					(thickness 0.15)
				)
			)
		)
		(property "Footprint" ""
			(at 160.02 71.12 0)
			(effects
				(font
					(size 1.27 1.27)
					(thickness 0.15)
				)
				(justify left bottom)
				(hide yes)
			)
		)
		(property "Datasheet" ""
			(at 160.02 76.2 0)
			(effects
				(font
					(size 1.27 1.27)
					(thickness 0.15)
				)
				(justify left bottom)
				(hide yes)
			)
		)
		(property "Description" ""
			(at 151.13 63.5 0)
			(effects
				(font
					(size 1.27 1.27)
				)
				(hide yes)
			)
		)
		(property "Author" "Antmicro"
			(at 160.02 71.12 0)
			(effects
				(font
					(size 1.27 1.27)
					(thickness 0.15)
				)
				(justify left bottom)
				(hide yes)
			)
		)
		(property "License" "Apache-2.0"
			(at 160.02 73.66 0)
			(effects
				(font
					(size 1.27 1.27)
					(thickness 0.15)
				)
				(justify left bottom)
				(hide yes)
			)
		)
		(pin "1"
		)
		(instances
			(project "jetson-orin-baseboard"
				(path ""
					(reference "#PWR024")
					(unit 1)
				)
			)
		)
	)
	(symbol
		(lib_id "antmicroPciConnectors:Bus_M.2_2199230-6")
		(at 191.77 160.02 0)
		(unit 1)
		(exclude_from_sim no)
		(in_bom yes)
		(on_board yes)
		(dnp no)
		(fields_autoplaced yes)
		(property "Reference" "J1"
			(at 207.01 151.13 0)
			(effects
				(font
					(size 1.27 1.27)
				)
			)
		)
		(property "Value" "Bus_M.2_2199230-6"
			(at 237.49 163.83 0)
			(effects
				(font
					(size 1.27 1.27)
					(thickness 0.15)
				)
				(justify left bottom)
				(hide yes)
			)
		)
		(property "Footprint" "antmicro-footprints:Bus_M.2_Socket_Key_E_TE_2199230-6"
			(at 237.49 166.37 0)
			(effects
				(font
					(size 1.27 1.27)
					(thickness 0.15)
				)
				(justify left bottom)
				(hide yes)
			)
		)
		(property "Datasheet" "https://www.te.com/usa-en/product-2199230-6.datasheet.pdf"
			(at 237.49 168.91 0)
			(effects
				(font
					(size 1.27 1.27)
					(thickness 0.15)
				)
				(justify left bottom)
				(hide yes)
			)
		)
		(property "Description" ""
			(at 191.77 160.02 0)
			(effects
				(font
					(size 1.27 1.27)
				)
				(hide yes)
			)
		)
		(property "MPN" "2199230-6 "
			(at 207.01 153.67 0)
			(effects
				(font
					(size 1.27 1.27)
					(thickness 0.15)
				)
			)
		)
		(property "Manufacturer" "TE Connectivity"
			(at 237.49 173.99 0)
			(effects
				(font
					(size 1.27 1.27)
					(thickness 0.15)
				)
				(justify left bottom)
				(hide yes)
			)
		)
		(property "Author" "Antmicro"
			(at 237.49 176.53 0)
			(effects
				(font
					(size 1.27 1.27)
					(thickness 0.15)
				)
				(justify left bottom)
				(hide yes)
			)
		)
		(property "License" "Apache-2.0"
			(at 237.49 179.07 0)
			(effects
				(font
					(size 1.27 1.27)
					(thickness 0.15)
				)
				(justify left bottom)
				(hide yes)
			)
		)
		(pin "1"
		)
		(pin "10"
		)
		(pin "11"
		)
		(pin "12"
		)
		(pin "13"
		)
		(pin "14"
		)
		(pin "15"
		)
		(pin "16"
		)
		(pin "17"
		)
		(pin "18"
		)
		(pin "19"
		)
		(pin "2"
		)
		(pin "20"
		)
		(pin "21"
		)
		(pin "22"
		)
		(pin "23"
		)
		(pin "3"
		)
		(pin "32"
		)
		(pin "33"
		)
		(pin "34"
		)
		(pin "35"
		)
		(pin "36"
		)
		(pin "37"
		)
		(pin "38"
		)
		(pin "39"
		)
		(pin "4"
		)
		(pin "40"
		)
		(pin "41"
		)
		(pin "42"
		)
		(pin "43"
		)
		(pin "44"
		)
		(pin "45"
		)
		(pin "46"
		)
		(pin "47"
		)
		(pin "48"
		)
		(pin "49"
		)
		(pin "5"
		)
		(pin "50"
		)
		(pin "51"
		)
		(pin "52"
		)
		(pin "53"
		)
		(pin "54"
		)
		(pin "55"
		)
		(pin "56"
		)
		(pin "57"
		)
		(pin "58"
		)
		(pin "59"
		)
		(pin "6"
		)
		(pin "60"
		)
		(pin "61"
		)
		(pin "62"
		)
		(pin "63"
		)
		(pin "64"
		)
		(pin "65"
		)
		(pin "66"
		)
		(pin "67"
		)
		(pin "68"
		)
		(pin "69"
		)
		(pin "7"
		)
		(pin "70"
		)
		(pin "71"
		)
		(pin "72"
		)
		(pin "73"
		)
		(pin "74"
		)
		(pin "75"
		)
		(pin "8"
		)
		(pin "9"
		)
		(pin "MP"
		)
		(instances
			(project "jetson-orin-baseboard"
				(path ""
					(reference "J1")
					(unit 1)
				)
			)
		)
	)
	(symbol
		(lib_id "antmicropower:+3V3")
		(at 254 224.79 0)
		(unit 1)
		(exclude_from_sim no)
		(in_bom yes)
		(on_board yes)
		(dnp no)
		(property "Reference" "#PWR0309"
			(at 254 228.6 0)
			(effects
				(font
					(size 1.27 1.27)
				)
				(justify left bottom)
				(hide yes)
			)
		)
		(property "Value" "+3V3"
			(at 250.825 221.615 0)
			(effects
				(font
					(size 1.27 1.27)
					(thickness 0.15)
				)
				(justify left bottom)
			)
		)
		(property "Footprint" ""
			(at 269.24 232.41 0)
			(effects
				(font
					(size 1.27 1.27)
					(thickness 0.15)
				)
				(justify left bottom)
				(hide yes)
			)
		)
		(property "Datasheet" ""
			(at 269.24 234.95 0)
			(effects
				(font
					(size 1.27 1.27)
					(thickness 0.15)
				)
				(justify left bottom)
				(hide yes)
			)
		)
		(property "Description" ""
			(at 254 224.79 0)
			(effects
				(font
					(size 1.27 1.27)
				)
				(hide yes)
			)
		)
		(property "Author" "Antmicro"
			(at 269.24 227.33 0)
			(effects
				(font
					(size 1.27 1.27)
					(thickness 0.15)
				)
				(justify left bottom)
				(hide yes)
			)
		)
		(property "License" "Apache-2.0"
			(at 269.24 229.87 0)
			(effects
				(font
					(size 1.27 1.27)
					(thickness 0.15)
				)
				(justify left bottom)
				(hide yes)
			)
		)
		(pin "1"
		)
		(instances
			(project "jetson-orin-baseboard"
				(path ""
					(reference "#PWR0309")
					(unit 1)
				)
			)
		)
	)
	(symbol
		(lib_id "antmicroResistors0402:R_0R_0402")
		(at 168.91 238.76 0)
		(unit 1)
		(exclude_from_sim no)
		(in_bom yes)
		(on_board yes)
		(dnp no)
		(property "Reference" "R20"
			(at 173.99 238.125 0)
			(effects
				(font
					(size 1.27 1.27)
				)
				(justify left bottom)
			)
		)
		(property "Value" "R_0R_0402"
			(at 189.23 251.46 0)
			(effects
				(font
					(size 1.27 1.27)
					(thickness 0.15)
				)
				(justify left bottom)
				(hide yes)
			)
		)
		(property "Footprint" "antmicro-footprints:R_0402_1005Metric"
			(at 189.23 254 0)
			(effects
				(font
					(size 1.27 1.27)
					(thickness 0.15)
				)
				(justify left bottom)
				(hide yes)
			)
		)
		(property "Datasheet" "https://industrial.panasonic.com/cdbs/www-data/pdf/RDA0000/AOA0000C301.pdf"
			(at 189.23 256.54 0)
			(effects
				(font
					(size 1.27 1.27)
					(thickness 0.15)
				)
				(justify left bottom)
				(hide yes)
			)
		)
		(property "Description" ""
			(at 168.91 238.76 0)
			(effects
				(font
					(size 1.27 1.27)
				)
				(hide yes)
			)
		)
		(property "Manufacturer" "Panasonic"
			(at 189.23 261.62 0)
			(effects
				(font
					(size 1.27 1.27)
					(thickness 0.15)
				)
				(justify left bottom)
				(hide yes)
			)
		)
		(property "MPN" "ERJ2GE0R00X"
			(at 189.23 259.08 0)
			(effects
				(font
					(size 1.27 1.27)
					(thickness 0.15)
				)
				(justify left bottom)
				(hide yes)
			)
		)
		(property "Val" "0R"
			(at 166.37 238.125 0)
			(effects
				(font
					(size 1.27 1.27)
					(thickness 0.15)
				)
				(justify left bottom)
			)
		)
		(property "License" "Apache-2.0"
			(at 189.23 264.16 0)
			(effects
				(font
					(size 1.27 1.27)
					(thickness 0.15)
				)
				(justify left bottom)
				(hide yes)
			)
		)
		(property "Author" "Antmicro"
			(at 189.23 266.7 0)
			(effects
				(font
					(size 1.27 1.27)
					(thickness 0.15)
				)
				(justify left bottom)
				(hide yes)
			)
		)
		(property "Tolerance" "~"
			(at 189.23 248.92 0)
			(effects
				(font
					(size 1.27 1.27)
				)
				(justify left bottom)
				(hide yes)
			)
		)
		(property "Current" "1A"
			(at 189.23 269.24 0)
			(effects
				(font
					(size 1.27 1.27)
					(thickness 0.15)
				)
				(justify left bottom)
				(hide yes)
			)
		)
		(pin "1"
		)
		(pin "2"
		)
		(instances
			(project "jetson-orin-baseboard"
				(path ""
					(reference "R20")
					(unit 1)
				)
			)
		)
	)
	(symbol
		(lib_name "C_100n_0402_1")
		(lib_id "antmicroCapacitors0402:C_100n_0402")
		(at 40.64 156.21 90)
		(mirror x)
		(unit 1)
		(exclude_from_sim no)
		(in_bom yes)
		(on_board yes)
		(dnp no)
		(fields_autoplaced yes)
		(property "Reference" "C25"
			(at 38.1 157.4863 90)
			(effects
				(font
					(size 1.27 1.27)
				)
				(justify left)
			)
		)
		(property "Value" "C_100n_0402"
			(at 50.8 176.53 0)
			(effects
				(font
					(size 1.27 1.27)
					(thickness 0.15)
				)
				(justify left bottom)
				(hide yes)
			)
		)
		(property "Footprint" "antmicro-footprints:C_0402_1005Metric"
			(at 53.34 176.53 0)
			(effects
				(font
					(size 1.27 1.27)
					(thickness 0.15)
				)
				(justify left bottom)
				(hide yes)
			)
		)
		(property "Datasheet" "https://www.murata.com/products/productdetail?partno=GRM155R61H104KE14%23"
			(at 55.88 176.53 0)
			(effects
				(font
					(size 1.27 1.27)
					(thickness 0.15)
				)
				(justify left bottom)
				(hide yes)
			)
		)
		(property "Description" ""
			(at 40.64 156.21 0)
			(effects
				(font
					(size 1.27 1.27)
				)
				(hide yes)
			)
		)
		(property "Manufacturer" "Murata"
			(at 60.96 176.53 0)
			(effects
				(font
					(size 1.27 1.27)
					(thickness 0.15)
				)
				(justify left bottom)
				(hide yes)
			)
		)
		(property "MPN" "GRM155R61H104KE14D"
			(at 58.42 176.53 0)
			(effects
				(font
					(size 1.27 1.27)
					(thickness 0.15)
				)
				(justify left bottom)
				(hide yes)
			)
		)
		(property "Val" "100n"
			(at 38.1 160.0263 90)
			(effects
				(font
					(size 1.27 1.27)
					(thickness 0.15)
				)
				(justify left)
			)
		)
		(property "License" "Apache-2.0"
			(at 63.5 176.53 0)
			(effects
				(font
					(size 1.27 1.27)
					(thickness 0.15)
				)
				(justify left bottom)
				(hide yes)
			)
		)
		(property "Author" "Antmicro"
			(at 66.04 176.53 0)
			(effects
				(font
					(size 1.27 1.27)
					(thickness 0.15)
				)
				(justify left bottom)
				(hide yes)
			)
		)
		(property "Voltage" "50V"
			(at 68.58 176.53 0)
			(effects
				(font
					(size 1.27 1.27)
				)
				(justify left bottom)
				(hide yes)
			)
		)
		(property "Dielectric" "X5R"
			(at 71.12 176.53 0)
			(effects
				(font
					(size 1.27 1.27)
				)
				(justify left bottom)
				(hide yes)
			)
		)
		(pin "1"
		)
		(pin "2"
		)
		(instances
			(project "jetson-orin-baseboard"
				(path ""
					(reference "C25")
					(unit 1)
				)
			)
		)
	)
	(symbol
		(lib_id "antmicropower:PWR_FLAG")
		(at 344.17 27.94 0)
		(unit 1)
		(exclude_from_sim no)
		(in_bom yes)
		(on_board yes)
		(dnp no)
		(property "Reference" "#FLG02"
			(at 344.17 26.035 0)
			(effects
				(font
					(size 1.27 1.27)
				)
				(hide yes)
			)
		)
		(property "Value" "PWR_FLAG"
			(at 344.17 24.13 0)
			(effects
				(font
					(size 1.27 1.27)
				)
			)
		)
		(property "Footprint" ""
			(at 344.17 27.94 0)
			(effects
				(font
					(size 1.27 1.27)
				)
				(hide yes)
			)
		)
		(property "Datasheet" ""
			(at 344.17 27.94 0)
			(effects
				(font
					(size 1.27 1.27)
				)
				(hide yes)
			)
		)
		(property "Description" ""
			(at 344.17 27.94 0)
			(effects
				(font
					(size 1.27 1.27)
				)
				(hide yes)
			)
		)
		(pin "1"
		)
		(instances
			(project "jetson-orin-baseboard"
				(path ""
					(reference "#FLG02")
					(unit 1)
				)
			)
		)
	)
	(symbol
		(lib_name "GND_4")
		(lib_id "antmicropower:GND")
		(at 344.17 111.76 0)
		(unit 1)
		(exclude_from_sim no)
		(in_bom yes)
		(on_board yes)
		(dnp no)
		(property "Reference" "#PWR036"
			(at 344.17 118.11 0)
			(effects
				(font
					(size 1.27 1.27)
				)
				(justify left bottom)
				(hide yes)
			)
		)
		(property "Value" "GND"
			(at 342.265 116.205 0)
			(effects
				(font
					(size 1.27 1.27)
					(thickness 0.15)
				)
				(justify left bottom)
			)
		)
		(property "Footprint" ""
			(at 353.06 119.38 0)
			(effects
				(font
					(size 1.27 1.27)
					(thickness 0.15)
				)
				(justify left bottom)
				(hide yes)
			)
		)
		(property "Datasheet" ""
			(at 353.06 124.46 0)
			(effects
				(font
					(size 1.27 1.27)
					(thickness 0.15)
				)
				(justify left bottom)
				(hide yes)
			)
		)
		(property "Description" ""
			(at 344.17 111.76 0)
			(effects
				(font
					(size 1.27 1.27)
				)
				(hide yes)
			)
		)
		(property "Author" "Antmicro"
			(at 353.06 119.38 0)
			(effects
				(font
					(size 1.27 1.27)
					(thickness 0.15)
				)
				(justify left bottom)
				(hide yes)
			)
		)
		(property "License" "Apache-2.0"
			(at 353.06 121.92 0)
			(effects
				(font
					(size 1.27 1.27)
					(thickness 0.15)
				)
				(justify left bottom)
				(hide yes)
			)
		)
		(pin "1"
		)
		(instances
			(project "jetson-orin-baseboard"
				(path ""
					(reference "#PWR036")
					(unit 1)
				)
			)
		)
	)
	(symbol
		(lib_name "GND_3")
		(lib_id "antmicropower:GND")
		(at 369.57 35.56 0)
		(unit 1)
		(exclude_from_sim no)
		(in_bom yes)
		(on_board yes)
		(dnp no)
		(property "Reference" "#PWR039"
			(at 369.57 41.91 0)
			(effects
				(font
					(size 1.27 1.27)
				)
				(justify left bottom)
				(hide yes)
			)
		)
		(property "Value" "GND"
			(at 367.665 40.005 0)
			(effects
				(font
					(size 1.27 1.27)
					(thickness 0.15)
				)
				(justify left bottom)
			)
		)
		(property "Footprint" ""
			(at 378.46 43.18 0)
			(effects
				(font
					(size 1.27 1.27)
					(thickness 0.15)
				)
				(justify left bottom)
				(hide yes)
			)
		)
		(property "Datasheet" ""
			(at 378.46 48.26 0)
			(effects
				(font
					(size 1.27 1.27)
					(thickness 0.15)
				)
				(justify left bottom)
				(hide yes)
			)
		)
		(property "Description" ""
			(at 369.57 35.56 0)
			(effects
				(font
					(size 1.27 1.27)
				)
				(hide yes)
			)
		)
		(property "Author" "Antmicro"
			(at 378.46 43.18 0)
			(effects
				(font
					(size 1.27 1.27)
					(thickness 0.15)
				)
				(justify left bottom)
				(hide yes)
			)
		)
		(property "License" "Apache-2.0"
			(at 378.46 45.72 0)
			(effects
				(font
					(size 1.27 1.27)
					(thickness 0.15)
				)
				(justify left bottom)
				(hide yes)
			)
		)
		(pin "1"
		)
		(instances
			(project "jetson-orin-baseboard"
				(path ""
					(reference "#PWR039")
					(unit 1)
				)
			)
		)
	)
	(symbol
		(lib_name "GND_1")
		(lib_id "antmicropower:GND")
		(at 40.64 162.56 0)
		(unit 1)
		(exclude_from_sim no)
		(in_bom yes)
		(on_board yes)
		(dnp no)
		(property "Reference" "#PWR016"
			(at 40.64 168.91 0)
			(effects
				(font
					(size 1.27 1.27)
				)
				(justify left bottom)
				(hide yes)
			)
		)
		(property "Value" "GND"
			(at 40.64 166.37 0)
			(effects
				(font
					(size 1.27 1.27)
					(thickness 0.15)
				)
			)
		)
		(property "Footprint" ""
			(at 49.53 170.18 0)
			(effects
				(font
					(size 1.27 1.27)
					(thickness 0.15)
				)
				(justify left bottom)
				(hide yes)
			)
		)
		(property "Datasheet" ""
			(at 49.53 175.26 0)
			(effects
				(font
					(size 1.27 1.27)
					(thickness 0.15)
				)
				(justify left bottom)
				(hide yes)
			)
		)
		(property "Description" ""
			(at 40.64 162.56 0)
			(effects
				(font
					(size 1.27 1.27)
				)
				(hide yes)
			)
		)
		(property "Author" "Antmicro"
			(at 49.53 170.18 0)
			(effects
				(font
					(size 1.27 1.27)
					(thickness 0.15)
				)
				(justify left bottom)
				(hide yes)
			)
		)
		(property "License" "Apache-2.0"
			(at 49.53 172.72 0)
			(effects
				(font
					(size 1.27 1.27)
					(thickness 0.15)
				)
				(justify left bottom)
				(hide yes)
			)
		)
		(pin "1"
		)
		(instances
			(project "jetson-orin-baseboard"
				(path ""
					(reference "#PWR016")
					(unit 1)
				)
			)
		)
	)
	(symbol
		(lib_id "antmicroMechanicalParts:Spacer_Drill3.7mm_H2.5mm_9774025151R")
		(at 284.48 275.59 180)
		(unit 1)
		(exclude_from_sim no)
		(in_bom yes)
		(on_board yes)
		(dnp no)
		(fields_autoplaced yes)
		(property "Reference" "SP7"
			(at 274.955 274.32 0)
			(effects
				(font
					(size 1.27 1.27)
					(thickness 0.15)
				)
				(justify left)
			)
		)
		(property "Value" "Spacer_Drill3.7mm_H2.5mm_9774025151R"
			(at 274.955 276.86 0)
			(effects
				(font
					(size 1.27 1.27)
					(thickness 0.15)
				)
				(justify left)
			)
		)
		(property "Footprint" "antmicro-footprints:Spacer_Drill3.7mm_H2.5mm_9774025151R"
			(at 261.62 267.97 0)
			(effects
				(font
					(size 1.27 1.27)
					(thickness 0.15)
				)
				(justify left bottom)
				(hide yes)
			)
		)
		(property "Datasheet" "https://www.we-online.com/components/products/datasheet/9774025151R.pdf"
			(at 261.62 265.43 0)
			(effects
				(font
					(size 1.27 1.27)
					(thickness 0.15)
				)
				(justify left bottom)
				(hide yes)
			)
		)
		(property "Description" ""
			(at 284.48 275.59 0)
			(effects
				(font
					(size 1.27 1.27)
				)
				(hide yes)
			)
		)
		(property "Manufacturer" "Würth Elektronik"
			(at 261.62 262.89 0)
			(effects
				(font
					(size 1.27 1.27)
					(thickness 0.15)
				)
				(justify left bottom)
				(hide yes)
			)
		)
		(property "MPN" "9774025151R"
			(at 261.62 260.35 0)
			(effects
				(font
					(size 1.27 1.27)
					(thickness 0.15)
				)
				(justify left bottom)
				(hide yes)
			)
		)
		(property "Author" "Antmicro"
			(at 261.62 257.81 0)
			(effects
				(font
					(size 1.27 1.27)
					(thickness 0.15)
				)
				(justify left bottom)
				(hide yes)
			)
		)
		(property "License" "Apache-2.0"
			(at 261.62 255.27 0)
			(effects
				(font
					(size 1.27 1.27)
					(thickness 0.15)
				)
				(justify left bottom)
				(hide yes)
			)
		)
		(pin "1"
		)
		(instances
			(project "jetson-orin-baseboard"
				(path ""
					(reference "SP7")
					(unit 1)
				)
			)
		)
	)
	(symbol
		(lib_id "antmicroResistors0402:R_200R_0402")
		(at 241.3 232.41 90)
		(unit 1)
		(exclude_from_sim no)
		(in_bom yes)
		(on_board yes)
		(dnp no)
		(property "Reference" "R186"
			(at 242.57 228.6 90)
			(effects
				(font
					(size 1.27 1.27)
				)
				(justify right)
			)
		)
		(property "Value" "R_200R_0402"
			(at 254 212.09 0)
			(effects
				(font
					(size 1.27 1.27)
					(thickness 0.15)
				)
				(justify left bottom)
				(hide yes)
			)
		)
		(property "Footprint" "antmicro-footprints:R_0402_1005Metric"
			(at 256.54 212.09 0)
			(effects
				(font
					(size 1.27 1.27)
					(thickness 0.15)
				)
				(justify left bottom)
				(hide yes)
			)
		)
		(property "Datasheet" "https://www.bourns.com/docs/product-datasheets/cr.pdf"
			(at 259.08 212.09 0)
			(effects
				(font
					(size 1.27 1.27)
					(thickness 0.15)
				)
				(justify left bottom)
				(hide yes)
			)
		)
		(property "Description" ""
			(at 241.3 232.41 0)
			(effects
				(font
					(size 1.27 1.27)
				)
				(hide yes)
			)
		)
		(property "Manufacturer" "Bourns"
			(at 264.16 212.09 0)
			(effects
				(font
					(size 1.27 1.27)
					(thickness 0.15)
				)
				(justify left bottom)
				(hide yes)
			)
		)
		(property "MPN" "CR0402-FX-2000GLF"
			(at 261.62 212.09 0)
			(effects
				(font
					(size 1.27 1.27)
					(thickness 0.15)
				)
				(justify left bottom)
				(hide yes)
			)
		)
		(property "Val" "200R"
			(at 242.57 231.14 90)
			(effects
				(font
					(size 1.27 1.27)
					(thickness 0.15)
				)
				(justify right)
			)
		)
		(property "License" "Apache-2.0"
			(at 266.7 212.09 0)
			(effects
				(font
					(size 1.27 1.27)
					(thickness 0.15)
				)
				(justify left bottom)
				(hide yes)
			)
		)
		(property "Author" "Antmicro"
			(at 269.24 212.09 0)
			(effects
				(font
					(size 1.27 1.27)
					(thickness 0.15)
				)
				(justify left bottom)
				(hide yes)
			)
		)
		(property "Tolerance" "1%"
			(at 251.46 212.09 0)
			(effects
				(font
					(size 1.27 1.27)
				)
				(justify left bottom)
				(hide yes)
			)
		)
		(pin "1"
		)
		(pin "2"
		)
		(instances
			(project "jetson-orin-baseboard"
				(path ""
					(reference "R186")
					(unit 1)
				)
			)
		)
	)
	(symbol
		(lib_id "antmicroResistors0402:R_0R_0402")
		(at 246.38 172.72 0)
		(unit 1)
		(exclude_from_sim no)
		(in_bom yes)
		(on_board yes)
		(dnp no)
		(property "Reference" "R29"
			(at 251.46 172.085 0)
			(effects
				(font
					(size 1.27 1.27)
				)
				(justify left bottom)
			)
		)
		(property "Value" "R_0R_0402"
			(at 266.7 185.42 0)
			(effects
				(font
					(size 1.27 1.27)
					(thickness 0.15)
				)
				(justify left bottom)
				(hide yes)
			)
		)
		(property "Footprint" "antmicro-footprints:R_0402_1005Metric"
			(at 266.7 187.96 0)
			(effects
				(font
					(size 1.27 1.27)
					(thickness 0.15)
				)
				(justify left bottom)
				(hide yes)
			)
		)
		(property "Datasheet" "https://industrial.panasonic.com/cdbs/www-data/pdf/RDA0000/AOA0000C301.pdf"
			(at 266.7 190.5 0)
			(effects
				(font
					(size 1.27 1.27)
					(thickness 0.15)
				)
				(justify left bottom)
				(hide yes)
			)
		)
		(property "Description" ""
			(at 246.38 172.72 0)
			(effects
				(font
					(size 1.27 1.27)
				)
				(hide yes)
			)
		)
		(property "Manufacturer" "Panasonic"
			(at 266.7 195.58 0)
			(effects
				(font
					(size 1.27 1.27)
					(thickness 0.15)
				)
				(justify left bottom)
				(hide yes)
			)
		)
		(property "MPN" "ERJ2GE0R00X"
			(at 266.7 193.04 0)
			(effects
				(font
					(size 1.27 1.27)
					(thickness 0.15)
				)
				(justify left bottom)
				(hide yes)
			)
		)
		(property "Val" "0R"
			(at 243.84 172.085 0)
			(effects
				(font
					(size 1.27 1.27)
					(thickness 0.15)
				)
				(justify left bottom)
			)
		)
		(property "License" "Apache-2.0"
			(at 266.7 198.12 0)
			(effects
				(font
					(size 1.27 1.27)
					(thickness 0.15)
				)
				(justify left bottom)
				(hide yes)
			)
		)
		(property "Author" "Antmicro"
			(at 266.7 200.66 0)
			(effects
				(font
					(size 1.27 1.27)
					(thickness 0.15)
				)
				(justify left bottom)
				(hide yes)
			)
		)
		(property "Tolerance" "~"
			(at 266.7 182.88 0)
			(effects
				(font
					(size 1.27 1.27)
				)
				(justify left bottom)
				(hide yes)
			)
		)
		(property "Current" "1A"
			(at 266.7 203.2 0)
			(effects
				(font
					(size 1.27 1.27)
					(thickness 0.15)
				)
				(justify left bottom)
				(hide yes)
			)
		)
		(pin "1"
		)
		(pin "2"
		)
		(instances
			(project "jetson-orin-baseboard"
				(path ""
					(reference "R29")
					(unit 1)
				)
			)
		)
	)
	(symbol
		(lib_id "antmicroResistorNetworksArrays:R_4x0R_0201_array")
		(at 307.34 207.01 0)
		(mirror y)
		(unit 1)
		(exclude_from_sim no)
		(in_bom yes)
		(on_board yes)
		(dnp no)
		(fields_autoplaced yes)
		(property "Reference" "R22"
			(at 302.26 200.66 0)
			(effects
				(font
					(size 1.27 1.27)
				)
			)
		)
		(property "Value" "R_4x0R_0201_array"
			(at 280.67 214.63 0)
			(effects
				(font
					(size 1.27 1.27)
					(thickness 0.15)
				)
				(justify left bottom)
				(hide yes)
			)
		)
		(property "Footprint" "antmicro-footprints:R_Array_4x0201_Panasonic_EXB18V"
			(at 280.67 219.71 0)
			(effects
				(font
					(size 1.27 1.27)
					(thickness 0.15)
				)
				(justify left bottom)
				(hide yes)
			)
		)
		(property "Datasheet" "http://industrial.panasonic.com/cdbs/www-data/pdf/AOC0000/AOC0000C14.pdf"
			(at 280.67 222.25 0)
			(effects
				(font
					(size 1.27 1.27)
					(thickness 0.15)
				)
				(justify left bottom)
				(hide yes)
			)
		)
		(property "Description" ""
			(at 307.34 207.01 0)
			(effects
				(font
					(size 1.27 1.27)
				)
				(hide yes)
			)
		)
		(property "MPN" "EXB-18VR000X"
			(at 280.67 224.79 0)
			(effects
				(font
					(size 1.27 1.27)
					(thickness 0.15)
				)
				(justify left bottom)
				(hide yes)
			)
		)
		(property "Manufacturer" "Panasonic"
			(at 280.67 227.33 0)
			(effects
				(font
					(size 1.27 1.27)
					(thickness 0.15)
				)
				(justify left bottom)
				(hide yes)
			)
		)
		(property "Val" "4x0R_0201"
			(at 302.26 203.2 0)
			(effects
				(font
					(size 1.27 1.27)
					(thickness 0.15)
				)
			)
		)
		(property "Author" "Antmicro"
			(at 280.67 229.87 0)
			(effects
				(font
					(size 1.27 1.27)
					(thickness 0.15)
				)
				(justify left bottom)
				(hide yes)
			)
		)
		(property "License" "Apache-2.0"
			(at 280.67 232.41 0)
			(effects
				(font
					(size 1.27 1.27)
					(thickness 0.15)
				)
				(justify left bottom)
				(hide yes)
			)
		)
		(pin "1"
		)
		(pin "2"
		)
		(pin "3"
		)
		(pin "4"
		)
		(pin "5"
		)
		(pin "6"
		)
		(pin "7"
		)
		(pin "8"
		)
		(instances
			(project "jetson-orin-baseboard"
				(path ""
					(reference "R22")
					(unit 1)
				)
			)
		)
	)
	(symbol
		(lib_name "GND_2")
		(lib_id "antmicropower:GND")
		(at 46.99 162.56 0)
		(unit 1)
		(exclude_from_sim no)
		(in_bom yes)
		(on_board yes)
		(dnp no)
		(property "Reference" "#PWR040"
			(at 46.99 168.91 0)
			(effects
				(font
					(size 1.27 1.27)
				)
				(justify left bottom)
				(hide yes)
			)
		)
		(property "Value" "GND"
			(at 46.99 166.37 0)
			(effects
				(font
					(size 1.27 1.27)
					(thickness 0.15)
				)
			)
		)
		(property "Footprint" ""
			(at 55.88 170.18 0)
			(effects
				(font
					(size 1.27 1.27)
					(thickness 0.15)
				)
				(justify left bottom)
				(hide yes)
			)
		)
		(property "Datasheet" ""
			(at 55.88 175.26 0)
			(effects
				(font
					(size 1.27 1.27)
					(thickness 0.15)
				)
				(justify left bottom)
				(hide yes)
			)
		)
		(property "Description" ""
			(at 46.99 162.56 0)
			(effects
				(font
					(size 1.27 1.27)
				)
				(hide yes)
			)
		)
		(property "Author" "Antmicro"
			(at 55.88 170.18 0)
			(effects
				(font
					(size 1.27 1.27)
					(thickness 0.15)
				)
				(justify left bottom)
				(hide yes)
			)
		)
		(property "License" "Apache-2.0"
			(at 55.88 172.72 0)
			(effects
				(font
					(size 1.27 1.27)
					(thickness 0.15)
				)
				(justify left bottom)
				(hide yes)
			)
		)
		(pin "1"
		)
		(instances
			(project "jetson-orin-baseboard"
				(path ""
					(reference "#PWR040")
					(unit 1)
				)
			)
		)
	)
	(symbol
		(lib_name "C_220n_0402_2")
		(lib_id "antmicroCapacitors0402:C_220n_0402")
		(at 285.75 57.15 180)
		(unit 1)
		(exclude_from_sim no)
		(in_bom yes)
		(on_board yes)
		(dnp no)
		(property "Reference" "C17"
			(at 288.29 55.245 0)
			(effects
				(font
					(size 1.27 1.27)
				)
				(justify left bottom)
			)
		)
		(property "Value" "C_220n_0402"
			(at 265.43 46.99 0)
			(effects
				(font
					(size 1.27 1.27)
					(thickness 0.15)
				)
				(justify left bottom)
				(hide yes)
			)
		)
		(property "Footprint" "antmicro-footprints:C_0402_1005Metric"
			(at 265.43 44.45 0)
			(effects
				(font
					(size 1.27 1.27)
					(thickness 0.15)
				)
				(justify left bottom)
				(hide yes)
			)
		)
		(property "Datasheet" "https://www.yageo.com/en/Chart/Download/pdf/CC0402KRX5R6BB224"
			(at 265.43 41.91 0)
			(effects
				(font
					(size 1.27 1.27)
					(thickness 0.15)
				)
				(justify left bottom)
				(hide yes)
			)
		)
		(property "Description" ""
			(at 285.75 57.15 0)
			(effects
				(font
					(size 1.27 1.27)
				)
				(hide yes)
			)
		)
		(property "Manufacturer" "YAGEO"
			(at 265.43 36.83 0)
			(effects
				(font
					(size 1.27 1.27)
					(thickness 0.15)
				)
				(justify left bottom)
				(hide yes)
			)
		)
		(property "MPN" "CC0402KRX5R6BB224"
			(at 265.43 39.37 0)
			(effects
				(font
					(size 1.27 1.27)
					(thickness 0.15)
				)
				(justify left bottom)
				(hide yes)
			)
		)
		(property "Val" "220n"
			(at 281.94 57.785 0)
			(effects
				(font
					(size 1.27 1.27)
					(thickness 0.15)
				)
				(justify left bottom)
			)
		)
		(property "License" "Apache-2.0"
			(at 265.43 34.29 0)
			(effects
				(font
					(size 1.27 1.27)
					(thickness 0.15)
				)
				(justify left bottom)
				(hide yes)
			)
		)
		(property "Author" "Antmicro"
			(at 265.43 31.75 0)
			(effects
				(font
					(size 1.27 1.27)
					(thickness 0.15)
				)
				(justify left bottom)
				(hide yes)
			)
		)
		(property "Voltage" ""
			(at 265.43 29.21 0)
			(effects
				(font
					(size 1.27 1.27)
				)
				(justify left bottom)
				(hide yes)
			)
		)
		(property "Dielectric" ""
			(at 265.43 26.67 0)
			(effects
				(font
					(size 1.27 1.27)
				)
				(justify left bottom)
				(hide yes)
			)
		)
		(pin "1"
		)
		(pin "2"
		)
		(instances
			(project "jetson-orin-baseboard"
				(path ""
					(reference "C17")
					(unit 1)
				)
			)
		)
	)
	(symbol
		(lib_name "R_0R_0402_1")
		(lib_id "antmicroResistors0402:R_0R_0402")
		(at 64.77 39.37 0)
		(unit 1)
		(exclude_from_sim no)
		(in_bom yes)
		(on_board yes)
		(dnp no)
		(property "Reference" "R18"
			(at 69.85 38.735 0)
			(effects
				(font
					(size 1.27 1.27)
				)
				(justify left bottom)
			)
		)
		(property "Value" "R_0R_0402"
			(at 85.09 52.07 0)
			(effects
				(font
					(size 1.27 1.27)
					(thickness 0.15)
				)
				(justify left bottom)
				(hide yes)
			)
		)
		(property "Footprint" "antmicro-footprints:R_0402_1005Metric"
			(at 85.09 54.61 0)
			(effects
				(font
					(size 1.27 1.27)
					(thickness 0.15)
				)
				(justify left bottom)
				(hide yes)
			)
		)
		(property "Datasheet" "https://industrial.panasonic.com/cdbs/www-data/pdf/RDA0000/AOA0000C301.pdf"
			(at 85.09 57.15 0)
			(effects
				(font
					(size 1.27 1.27)
					(thickness 0.15)
				)
				(justify left bottom)
				(hide yes)
			)
		)
		(property "Description" ""
			(at 64.77 39.37 0)
			(effects
				(font
					(size 1.27 1.27)
				)
				(hide yes)
			)
		)
		(property "Manufacturer" "Panasonic"
			(at 85.09 62.23 0)
			(effects
				(font
					(size 1.27 1.27)
					(thickness 0.15)
				)
				(justify left bottom)
				(hide yes)
			)
		)
		(property "MPN" "ERJ2GE0R00X"
			(at 85.09 59.69 0)
			(effects
				(font
					(size 1.27 1.27)
					(thickness 0.15)
				)
				(justify left bottom)
				(hide yes)
			)
		)
		(property "Val" "0R"
			(at 62.23 38.735 0)
			(effects
				(font
					(size 1.27 1.27)
					(thickness 0.15)
				)
				(justify left bottom)
			)
		)
		(property "License" "Apache-2.0"
			(at 85.09 64.77 0)
			(effects
				(font
					(size 1.27 1.27)
					(thickness 0.15)
				)
				(justify left bottom)
				(hide yes)
			)
		)
		(property "Author" "Antmicro"
			(at 85.09 67.31 0)
			(effects
				(font
					(size 1.27 1.27)
					(thickness 0.15)
				)
				(justify left bottom)
				(hide yes)
			)
		)
		(property "Tolerance" "~"
			(at 85.09 49.53 0)
			(effects
				(font
					(size 1.27 1.27)
				)
				(justify left bottom)
				(hide yes)
			)
		)
		(property "Current" "1A"
			(at 85.09 69.85 0)
			(effects
				(font
					(size 1.27 1.27)
					(thickness 0.15)
				)
				(justify left bottom)
				(hide yes)
			)
		)
		(pin "1"
		)
		(pin "2"
		)
		(instances
			(project "jetson-orin-baseboard"
				(path ""
					(reference "R18")
					(unit 1)
				)
			)
		)
	)
	(symbol
		(lib_id "antmicroResistorNetworksArrays:R_4x0R_0201_array")
		(at 157.48 226.06 0)
		(unit 1)
		(exclude_from_sim no)
		(in_bom yes)
		(on_board yes)
		(dnp no)
		(fields_autoplaced yes)
		(property "Reference" "R21"
			(at 162.56 219.71 0)
			(effects
				(font
					(size 1.27 1.27)
				)
			)
		)
		(property "Value" "R_4x0R_0201_array"
			(at 184.15 233.68 0)
			(effects
				(font
					(size 1.27 1.27)
					(thickness 0.15)
				)
				(justify left bottom)
				(hide yes)
			)
		)
		(property "Footprint" "antmicro-footprints:R_Array_4x0201_Panasonic_EXB18V"
			(at 184.15 238.76 0)
			(effects
				(font
					(size 1.27 1.27)
					(thickness 0.15)
				)
				(justify left bottom)
				(hide yes)
			)
		)
		(property "Datasheet" "http://industrial.panasonic.com/cdbs/www-data/pdf/AOC0000/AOC0000C14.pdf"
			(at 184.15 241.3 0)
			(effects
				(font
					(size 1.27 1.27)
					(thickness 0.15)
				)
				(justify left bottom)
				(hide yes)
			)
		)
		(property "Description" ""
			(at 157.48 226.06 0)
			(effects
				(font
					(size 1.27 1.27)
				)
				(hide yes)
			)
		)
		(property "MPN" "EXB-18VR000X"
			(at 184.15 243.84 0)
			(effects
				(font
					(size 1.27 1.27)
					(thickness 0.15)
				)
				(justify left bottom)
				(hide yes)
			)
		)
		(property "Manufacturer" "Panasonic"
			(at 184.15 246.38 0)
			(effects
				(font
					(size 1.27 1.27)
					(thickness 0.15)
				)
				(justify left bottom)
				(hide yes)
			)
		)
		(property "Val" "4x0R_0201"
			(at 162.56 222.25 0)
			(effects
				(font
					(size 1.27 1.27)
					(thickness 0.15)
				)
			)
		)
		(property "Author" "Antmicro"
			(at 184.15 248.92 0)
			(effects
				(font
					(size 1.27 1.27)
					(thickness 0.15)
				)
				(justify left bottom)
				(hide yes)
			)
		)
		(property "License" "Apache-2.0"
			(at 184.15 251.46 0)
			(effects
				(font
					(size 1.27 1.27)
					(thickness 0.15)
				)
				(justify left bottom)
				(hide yes)
			)
		)
		(pin "1"
		)
		(pin "2"
		)
		(pin "3"
		)
		(pin "4"
		)
		(pin "5"
		)
		(pin "6"
		)
		(pin "7"
		)
		(pin "8"
		)
		(instances
			(project "jetson-orin-baseboard"
				(path ""
					(reference "R21")
					(unit 1)
				)
			)
		)
	)
	(symbol
		(lib_name "LED_G_0603_LTST-C190GKT_1")
		(lib_id "antmicroLEDIndicationDiscrete:LED_G_0603_LTST-C190GKT")
		(at 344.17 85.09 90)
		(unit 1)
		(exclude_from_sim no)
		(in_bom yes)
		(on_board yes)
		(dnp no)
		(fields_autoplaced yes)
		(property "Reference" "D1"
			(at 346.71 81.28 90)
			(effects
				(font
					(size 1.27 1.27)
				)
				(justify right)
			)
		)
		(property "Value" "LED_G_0603_LTST-C190GKT"
			(at 351.79 62.23 0)
			(effects
				(font
					(size 1.27 1.27)
					(thickness 0.15)
				)
				(justify left bottom)
				(hide yes)
			)
		)
		(property "Footprint" "antmicro-footprints:LED_0603_1608Metric_G"
			(at 354.33 62.23 0)
			(effects
				(font
					(size 1.27 1.27)
					(thickness 0.15)
				)
				(justify left bottom)
				(hide yes)
			)
		)
		(property "Datasheet" "https://media.digikey.com/pdf/Data%20Sheets/Lite-On%20PDFs/LTST-C190GKT.pdf"
			(at 356.87 62.23 0)
			(effects
				(font
					(size 1.27 1.27)
					(thickness 0.15)
				)
				(justify left bottom)
				(hide yes)
			)
		)
		(property "Description" ""
			(at 344.17 85.09 0)
			(effects
				(font
					(size 1.27 1.27)
				)
				(hide yes)
			)
		)
		(property "MPN" "LTST-C190GKT"
			(at 359.41 62.23 0)
			(effects
				(font
					(size 1.27 1.27)
					(thickness 0.15)
				)
				(justify left bottom)
				(hide yes)
			)
		)
		(property "Manufacturer" "Lite-On"
			(at 361.95 62.23 0)
			(effects
				(font
					(size 1.27 1.27)
					(thickness 0.15)
				)
				(justify left bottom)
				(hide yes)
			)
		)
		(property "Author" "Antmicro"
			(at 364.49 62.23 0)
			(effects
				(font
					(size 1.27 1.27)
					(thickness 0.15)
				)
				(justify left bottom)
				(hide yes)
			)
		)
		(property "License" "Apache-2.0"
			(at 367.03 62.23 0)
			(effects
				(font
					(size 1.27 1.27)
					(thickness 0.15)
				)
				(justify left bottom)
				(hide yes)
			)
		)
		(property "Color" "Green"
			(at 346.71 83.82 90)
			(effects
				(font
					(size 1.27 1.27)
				)
				(justify right)
			)
		)
		(pin "1"
		)
		(pin "2"
		)
		(instances
			(project "jetson-orin-baseboard"
				(path ""
					(reference "D1")
					(unit 1)
				)
			)
		)
	)
	(symbol
		(lib_name "C_220n_0402_3")
		(lib_id "antmicroCapacitors0402:C_220n_0402")
		(at 283.21 85.09 180)
		(unit 1)
		(exclude_from_sim no)
		(in_bom yes)
		(on_board yes)
		(dnp no)
		(property "Reference" "C15"
			(at 285.75 83.185 0)
			(effects
				(font
					(size 1.27 1.27)
				)
				(justify left bottom)
			)
		)
		(property "Value" "C_220n_0402"
			(at 262.89 74.93 0)
			(effects
				(font
					(size 1.27 1.27)
					(thickness 0.15)
				)
				(justify left bottom)
				(hide yes)
			)
		)
		(property "Footprint" "antmicro-footprints:C_0402_1005Metric"
			(at 262.89 72.39 0)
			(effects
				(font
					(size 1.27 1.27)
					(thickness 0.15)
				)
				(justify left bottom)
				(hide yes)
			)
		)
		(property "Datasheet" "https://www.yageo.com/en/Chart/Download/pdf/CC0402KRX5R6BB224"
			(at 262.89 69.85 0)
			(effects
				(font
					(size 1.27 1.27)
					(thickness 0.15)
				)
				(justify left bottom)
				(hide yes)
			)
		)
		(property "Description" ""
			(at 283.21 85.09 0)
			(effects
				(font
					(size 1.27 1.27)
				)
				(hide yes)
			)
		)
		(property "Manufacturer" "YAGEO"
			(at 262.89 64.77 0)
			(effects
				(font
					(size 1.27 1.27)
					(thickness 0.15)
				)
				(justify left bottom)
				(hide yes)
			)
		)
		(property "MPN" "CC0402KRX5R6BB224"
			(at 262.89 67.31 0)
			(effects
				(font
					(size 1.27 1.27)
					(thickness 0.15)
				)
				(justify left bottom)
				(hide yes)
			)
		)
		(property "Val" "220n"
			(at 279.4 85.725 0)
			(effects
				(font
					(size 1.27 1.27)
					(thickness 0.15)
				)
				(justify left bottom)
			)
		)
		(property "License" "Apache-2.0"
			(at 262.89 62.23 0)
			(effects
				(font
					(size 1.27 1.27)
					(thickness 0.15)
				)
				(justify left bottom)
				(hide yes)
			)
		)
		(property "Author" "Antmicro"
			(at 262.89 59.69 0)
			(effects
				(font
					(size 1.27 1.27)
					(thickness 0.15)
				)
				(justify left bottom)
				(hide yes)
			)
		)
		(property "Voltage" ""
			(at 262.89 57.15 0)
			(effects
				(font
					(size 1.27 1.27)
				)
				(justify left bottom)
				(hide yes)
			)
		)
		(property "Dielectric" ""
			(at 262.89 54.61 0)
			(effects
				(font
					(size 1.27 1.27)
				)
				(justify left bottom)
				(hide yes)
			)
		)
		(pin "1"
		)
		(pin "2"
		)
		(instances
			(project "jetson-orin-baseboard"
				(path ""
					(reference "C15")
					(unit 1)
				)
			)
		)
	)
	(symbol
		(lib_id "antmicropower:+3V3")
		(at 241.3 224.79 0)
		(unit 1)
		(exclude_from_sim no)
		(in_bom yes)
		(on_board yes)
		(dnp no)
		(property "Reference" "#PWR0311"
			(at 241.3 228.6 0)
			(effects
				(font
					(size 1.27 1.27)
				)
				(justify left bottom)
				(hide yes)
			)
		)
		(property "Value" "+3V3"
			(at 238.125 221.615 0)
			(effects
				(font
					(size 1.27 1.27)
					(thickness 0.15)
				)
				(justify left bottom)
			)
		)
		(property "Footprint" ""
			(at 256.54 232.41 0)
			(effects
				(font
					(size 1.27 1.27)
					(thickness 0.15)
				)
				(justify left bottom)
				(hide yes)
			)
		)
		(property "Datasheet" ""
			(at 256.54 234.95 0)
			(effects
				(font
					(size 1.27 1.27)
					(thickness 0.15)
				)
				(justify left bottom)
				(hide yes)
			)
		)
		(property "Description" ""
			(at 241.3 224.79 0)
			(effects
				(font
					(size 1.27 1.27)
				)
				(hide yes)
			)
		)
		(property "Author" "Antmicro"
			(at 256.54 227.33 0)
			(effects
				(font
					(size 1.27 1.27)
					(thickness 0.15)
				)
				(justify left bottom)
				(hide yes)
			)
		)
		(property "License" "Apache-2.0"
			(at 256.54 229.87 0)
			(effects
				(font
					(size 1.27 1.27)
					(thickness 0.15)
				)
				(justify left bottom)
				(hide yes)
			)
		)
		(pin "1"
		)
		(instances
			(project "jetson-orin-baseboard"
				(path ""
					(reference "#PWR0311")
					(unit 1)
				)
			)
		)
	)
	(symbol
		(lib_id "antmicroResistors0402:R_47k_0402")
		(at 175.26 153.67 90)
		(mirror x)
		(unit 1)
		(exclude_from_sim no)
		(in_bom no)
		(on_board yes)
		(dnp yes)
		(property "Reference" "R27"
			(at 176.53 154.94 90)
			(effects
				(font
					(size 1.27 1.27)
				)
				(justify right)
			)
		)
		(property "Value" "R_47k_0402"
			(at 187.96 173.99 0)
			(effects
				(font
					(size 1.27 1.27)
					(thickness 0.15)
				)
				(justify left bottom)
				(hide yes)
			)
		)
		(property "Footprint" "antmicro-footprints:R_0402_1005Metric"
			(at 190.5 173.99 0)
			(effects
				(font
					(size 1.27 1.27)
					(thickness 0.15)
				)
				(justify left bottom)
				(hide yes)
			)
		)
		(property "Datasheet" "https://www.bourns.com/docs/product-datasheets/cr.pdf"
			(at 193.04 173.99 0)
			(effects
				(font
					(size 1.27 1.27)
					(thickness 0.15)
				)
				(justify left bottom)
				(hide yes)
			)
		)
		(property "Description" ""
			(at 175.26 153.67 0)
			(effects
				(font
					(size 1.27 1.27)
				)
				(hide yes)
			)
		)
		(property "Manufacturer" "Bourns"
			(at 198.12 173.99 0)
			(effects
				(font
					(size 1.27 1.27)
					(thickness 0.15)
				)
				(justify left bottom)
				(hide yes)
			)
		)
		(property "MPN" "CR0402-FX-4702GLF"
			(at 195.58 173.99 0)
			(effects
				(font
					(size 1.27 1.27)
					(thickness 0.15)
				)
				(justify left bottom)
				(hide yes)
			)
		)
		(property "Val" "47k"
			(at 176.53 157.48 90)
			(effects
				(font
					(size 1.27 1.27)
					(thickness 0.15)
				)
				(justify right)
			)
		)
		(property "License" "Apache-2.0"
			(at 200.66 173.99 0)
			(effects
				(font
					(size 1.27 1.27)
					(thickness 0.15)
				)
				(justify left bottom)
				(hide yes)
			)
		)
		(property "Author" "Antmicro"
			(at 203.2 173.99 0)
			(effects
				(font
					(size 1.27 1.27)
					(thickness 0.15)
				)
				(justify left bottom)
				(hide yes)
			)
		)
		(property "Tolerance" "1%"
			(at 185.42 173.99 0)
			(effects
				(font
					(size 1.27 1.27)
				)
				(justify left bottom)
				(hide yes)
			)
		)
		(pin "1"
		)
		(pin "2"
		)
		(instances
			(project "jetson-orin-baseboard"
				(path ""
					(reference "R27")
					(unit 1)
				)
			)
		)
	)
	(symbol
		(lib_id "antmicroResistors0402:R_47k_0402")
		(at 184.15 153.67 90)
		(mirror x)
		(unit 1)
		(exclude_from_sim no)
		(in_bom no)
		(on_board yes)
		(dnp yes)
		(property "Reference" "R28"
			(at 185.42 154.94 90)
			(effects
				(font
					(size 1.27 1.27)
				)
				(justify right)
			)
		)
		(property "Value" "R_47k_0402"
			(at 196.85 173.99 0)
			(effects
				(font
					(size 1.27 1.27)
					(thickness 0.15)
				)
				(justify left bottom)
				(hide yes)
			)
		)
		(property "Footprint" "antmicro-footprints:R_0402_1005Metric"
			(at 199.39 173.99 0)
			(effects
				(font
					(size 1.27 1.27)
					(thickness 0.15)
				)
				(justify left bottom)
				(hide yes)
			)
		)
		(property "Datasheet" "https://www.bourns.com/docs/product-datasheets/cr.pdf"
			(at 201.93 173.99 0)
			(effects
				(font
					(size 1.27 1.27)
					(thickness 0.15)
				)
				(justify left bottom)
				(hide yes)
			)
		)
		(property "Description" ""
			(at 184.15 153.67 0)
			(effects
				(font
					(size 1.27 1.27)
				)
				(hide yes)
			)
		)
		(property "Manufacturer" "Bourns"
			(at 207.01 173.99 0)
			(effects
				(font
					(size 1.27 1.27)
					(thickness 0.15)
				)
				(justify left bottom)
				(hide yes)
			)
		)
		(property "MPN" "CR0402-FX-4702GLF"
			(at 204.47 173.99 0)
			(effects
				(font
					(size 1.27 1.27)
					(thickness 0.15)
				)
				(justify left bottom)
				(hide yes)
			)
		)
		(property "Val" "47k"
			(at 185.42 157.48 90)
			(effects
				(font
					(size 1.27 1.27)
					(thickness 0.15)
				)
				(justify right)
			)
		)
		(property "License" "Apache-2.0"
			(at 209.55 173.99 0)
			(effects
				(font
					(size 1.27 1.27)
					(thickness 0.15)
				)
				(justify left bottom)
				(hide yes)
			)
		)
		(property "Author" "Antmicro"
			(at 212.09 173.99 0)
			(effects
				(font
					(size 1.27 1.27)
					(thickness 0.15)
				)
				(justify left bottom)
				(hide yes)
			)
		)
		(property "Tolerance" "1%"
			(at 194.31 173.99 0)
			(effects
				(font
					(size 1.27 1.27)
				)
				(justify left bottom)
				(hide yes)
			)
		)
		(pin "1"
		)
		(pin "2"
		)
		(instances
			(project "jetson-orin-baseboard"
				(path ""
					(reference "R28")
					(unit 1)
				)
			)
		)
	)
	(symbol
		(lib_name "R_200R_0402_1")
		(lib_id "antmicroResistors0402:R_200R_0402")
		(at 344.17 77.47 90)
		(unit 1)
		(exclude_from_sim no)
		(in_bom yes)
		(on_board yes)
		(dnp no)
		(fields_autoplaced yes)
		(property "Reference" "R39"
			(at 346.71 73.66 90)
			(effects
				(font
					(size 1.27 1.27)
				)
				(justify right)
			)
		)
		(property "Value" "R_200R_0402"
			(at 356.87 57.15 0)
			(effects
				(font
					(size 1.27 1.27)
					(thickness 0.15)
				)
				(justify left bottom)
				(hide yes)
			)
		)
		(property "Footprint" "antmicro-footprints:R_0402_1005Metric"
			(at 359.41 57.15 0)
			(effects
				(font
					(size 1.27 1.27)
					(thickness 0.15)
				)
				(justify left bottom)
				(hide yes)
			)
		)
		(property "Datasheet" "https://www.bourns.com/docs/product-datasheets/cr.pdf"
			(at 361.95 57.15 0)
			(effects
				(font
					(size 1.27 1.27)
					(thickness 0.15)
				)
				(justify left bottom)
				(hide yes)
			)
		)
		(property "Description" ""
			(at 344.17 77.47 0)
			(effects
				(font
					(size 1.27 1.27)
				)
				(hide yes)
			)
		)
		(property "Manufacturer" "Bourns"
			(at 367.03 57.15 0)
			(effects
				(font
					(size 1.27 1.27)
					(thickness 0.15)
				)
				(justify left bottom)
				(hide yes)
			)
		)
		(property "MPN" "CR0402-FX-2000GLF"
			(at 364.49 57.15 0)
			(effects
				(font
					(size 1.27 1.27)
					(thickness 0.15)
				)
				(justify left bottom)
				(hide yes)
			)
		)
		(property "Val" "200R"
			(at 346.71 76.2 90)
			(effects
				(font
					(size 1.27 1.27)
					(thickness 0.15)
				)
				(justify right)
			)
		)
		(property "License" "Apache-2.0"
			(at 369.57 57.15 0)
			(effects
				(font
					(size 1.27 1.27)
					(thickness 0.15)
				)
				(justify left bottom)
				(hide yes)
			)
		)
		(property "Author" "Antmicro"
			(at 372.11 57.15 0)
			(effects
				(font
					(size 1.27 1.27)
					(thickness 0.15)
				)
				(justify left bottom)
				(hide yes)
			)
		)
		(property "Tolerance" "1%"
			(at 354.33 57.15 0)
			(effects
				(font
					(size 1.27 1.27)
				)
				(justify left bottom)
				(hide yes)
			)
		)
		(pin "1"
		)
		(pin "2"
		)
		(instances
			(project "jetson-orin-baseboard"
				(path ""
					(reference "R39")
					(unit 1)
				)
			)
		)
	)
	(symbol
		(lib_name "C_10u_0603_2")
		(lib_id "antmicroCapacitors0603:C_10u_0603")
		(at 369.57 30.48 90)
		(mirror x)
		(unit 1)
		(exclude_from_sim no)
		(in_bom yes)
		(on_board yes)
		(dnp no)
		(fields_autoplaced yes)
		(property "Reference" "C23"
			(at 372.11 31.7563 90)
			(effects
				(font
					(size 1.27 1.27)
				)
				(justify right)
			)
		)
		(property "Value" "C_10u_0603"
			(at 379.73 50.8 0)
			(effects
				(font
					(size 1.27 1.27)
					(thickness 0.15)
				)
				(justify left bottom)
				(hide yes)
			)
		)
		(property "Footprint" "antmicro-footprints:C_0603_1608Metric"
			(at 382.27 50.8 0)
			(effects
				(font
					(size 1.27 1.27)
					(thickness 0.15)
				)
				(justify left bottom)
				(hide yes)
			)
		)
		(property "Datasheet" "https://www.murata.com/products/productdetail?partno=GRM188R61A106KE69%23"
			(at 384.81 50.8 0)
			(effects
				(font
					(size 1.27 1.27)
					(thickness 0.15)
				)
				(justify left bottom)
				(hide yes)
			)
		)
		(property "Description" ""
			(at 369.57 30.48 0)
			(effects
				(font
					(size 1.27 1.27)
				)
				(hide yes)
			)
		)
		(property "Manufacturer" "Murata"
			(at 389.89 50.8 0)
			(effects
				(font
					(size 1.27 1.27)
					(thickness 0.15)
				)
				(justify left bottom)
				(hide yes)
			)
		)
		(property "MPN" "GRM188R61A106KE69D"
			(at 387.35 50.8 0)
			(effects
				(font
					(size 1.27 1.27)
					(thickness 0.15)
				)
				(justify left bottom)
				(hide yes)
			)
		)
		(property "Val" "10u"
			(at 372.11 34.2963 90)
			(effects
				(font
					(size 1.27 1.27)
					(thickness 0.15)
				)
				(justify right)
			)
		)
		(property "License" "Apache-2.0"
			(at 392.43 50.8 0)
			(effects
				(font
					(size 1.27 1.27)
					(thickness 0.15)
				)
				(justify left bottom)
				(hide yes)
			)
		)
		(property "Author" "Antmicro"
			(at 394.97 50.8 0)
			(effects
				(font
					(size 1.27 1.27)
					(thickness 0.15)
				)
				(justify left bottom)
				(hide yes)
			)
		)
		(property "Voltage" ""
			(at 397.51 50.8 0)
			(effects
				(font
					(size 1.27 1.27)
				)
				(justify left bottom)
				(hide yes)
			)
		)
		(property "Dielectric" "template_dielectric"
			(at 400.05 50.8 0)
			(effects
				(font
					(size 1.27 1.27)
				)
				(justify left bottom)
				(hide yes)
			)
		)
		(pin "1"
		)
		(pin "2"
		)
		(instances
			(project "jetson-orin-baseboard"
				(path ""
					(reference "C23")
					(unit 1)
				)
			)
		)
	)
	(symbol
		(lib_name "C_220n_0402_4")
		(lib_id "antmicroCapacitors0402:C_220n_0402")
		(at 285.75 72.39 180)
		(unit 1)
		(exclude_from_sim no)
		(in_bom yes)
		(on_board yes)
		(dnp no)
		(property "Reference" "C18"
			(at 288.29 70.485 0)
			(effects
				(font
					(size 1.27 1.27)
				)
				(justify left bottom)
			)
		)
		(property "Value" "C_220n_0402"
			(at 265.43 62.23 0)
			(effects
				(font
					(size 1.27 1.27)
					(thickness 0.15)
				)
				(justify left bottom)
				(hide yes)
			)
		)
		(property "Footprint" "antmicro-footprints:C_0402_1005Metric"
			(at 265.43 59.69 0)
			(effects
				(font
					(size 1.27 1.27)
					(thickness 0.15)
				)
				(justify left bottom)
				(hide yes)
			)
		)
		(property "Datasheet" "https://www.yageo.com/en/Chart/Download/pdf/CC0402KRX5R6BB224"
			(at 265.43 57.15 0)
			(effects
				(font
					(size 1.27 1.27)
					(thickness 0.15)
				)
				(justify left bottom)
				(hide yes)
			)
		)
		(property "Description" ""
			(at 285.75 72.39 0)
			(effects
				(font
					(size 1.27 1.27)
				)
				(hide yes)
			)
		)
		(property "Manufacturer" "YAGEO"
			(at 265.43 52.07 0)
			(effects
				(font
					(size 1.27 1.27)
					(thickness 0.15)
				)
				(justify left bottom)
				(hide yes)
			)
		)
		(property "MPN" "CC0402KRX5R6BB224"
			(at 265.43 54.61 0)
			(effects
				(font
					(size 1.27 1.27)
					(thickness 0.15)
				)
				(justify left bottom)
				(hide yes)
			)
		)
		(property "Val" "220n"
			(at 281.94 73.025 0)
			(effects
				(font
					(size 1.27 1.27)
					(thickness 0.15)
				)
				(justify left bottom)
			)
		)
		(property "License" "Apache-2.0"
			(at 265.43 49.53 0)
			(effects
				(font
					(size 1.27 1.27)
					(thickness 0.15)
				)
				(justify left bottom)
				(hide yes)
			)
		)
		(property "Author" "Antmicro"
			(at 265.43 46.99 0)
			(effects
				(font
					(size 1.27 1.27)
					(thickness 0.15)
				)
				(justify left bottom)
				(hide yes)
			)
		)
		(property "Voltage" ""
			(at 265.43 44.45 0)
			(effects
				(font
					(size 1.27 1.27)
				)
				(justify left bottom)
				(hide yes)
			)
		)
		(property "Dielectric" ""
			(at 265.43 41.91 0)
			(effects
				(font
					(size 1.27 1.27)
				)
				(justify left bottom)
				(hide yes)
			)
		)
		(pin "1"
		)
		(pin "2"
		)
		(instances
			(project "jetson-orin-baseboard"
				(path ""
					(reference "C18")
					(unit 1)
				)
			)
		)
	)
	(symbol
		(lib_name "R_47k_0402_2")
		(lib_id "antmicroResistors0402:R_47k_0402")
		(at 295.91 26.67 90)
		(mirror x)
		(unit 1)
		(exclude_from_sim no)
		(in_bom no)
		(on_board yes)
		(dnp yes)
		(property "Reference" "R37"
			(at 297.18 27.94 90)
			(effects
				(font
					(size 1.27 1.27)
				)
				(justify right)
			)
		)
		(property "Value" "R_47k_0402"
			(at 308.61 46.99 0)
			(effects
				(font
					(size 1.27 1.27)
					(thickness 0.15)
				)
				(justify left bottom)
				(hide yes)
			)
		)
		(property "Footprint" "antmicro-footprints:R_0402_1005Metric"
			(at 311.15 46.99 0)
			(effects
				(font
					(size 1.27 1.27)
					(thickness 0.15)
				)
				(justify left bottom)
				(hide yes)
			)
		)
		(property "Datasheet" "https://www.bourns.com/docs/product-datasheets/cr.pdf"
			(at 313.69 46.99 0)
			(effects
				(font
					(size 1.27 1.27)
					(thickness 0.15)
				)
				(justify left bottom)
				(hide yes)
			)
		)
		(property "Description" ""
			(at 295.91 26.67 0)
			(effects
				(font
					(size 1.27 1.27)
				)
				(hide yes)
			)
		)
		(property "Manufacturer" "Bourns"
			(at 318.77 46.99 0)
			(effects
				(font
					(size 1.27 1.27)
					(thickness 0.15)
				)
				(justify left bottom)
				(hide yes)
			)
		)
		(property "MPN" "CR0402-FX-4702GLF"
			(at 316.23 46.99 0)
			(effects
				(font
					(size 1.27 1.27)
					(thickness 0.15)
				)
				(justify left bottom)
				(hide yes)
			)
		)
		(property "Val" "47k"
			(at 297.18 30.48 90)
			(effects
				(font
					(size 1.27 1.27)
					(thickness 0.15)
				)
				(justify right)
			)
		)
		(property "License" "Apache-2.0"
			(at 321.31 46.99 0)
			(effects
				(font
					(size 1.27 1.27)
					(thickness 0.15)
				)
				(justify left bottom)
				(hide yes)
			)
		)
		(property "Author" "Antmicro"
			(at 323.85 46.99 0)
			(effects
				(font
					(size 1.27 1.27)
					(thickness 0.15)
				)
				(justify left bottom)
				(hide yes)
			)
		)
		(property "Tolerance" "1%"
			(at 306.07 46.99 0)
			(effects
				(font
					(size 1.27 1.27)
				)
				(justify left bottom)
				(hide yes)
			)
		)
		(pin "1"
		)
		(pin "2"
		)
		(instances
			(project "jetson-orin-baseboard"
				(path ""
					(reference "R37")
					(unit 1)
				)
			)
		)
	)
	(symbol
		(lib_name "+3V3_4")
		(lib_id "antmicropower:+3V3")
		(at 344.17 71.12 0)
		(unit 1)
		(exclude_from_sim no)
		(in_bom yes)
		(on_board yes)
		(dnp no)
		(property "Reference" "#PWR0319"
			(at 344.17 74.93 0)
			(effects
				(font
					(size 1.27 1.27)
				)
				(justify left bottom)
				(hide yes)
			)
		)
		(property "Value" "+3V3"
			(at 340.995 67.945 0)
			(effects
				(font
					(size 1.27 1.27)
					(thickness 0.15)
				)
				(justify left bottom)
			)
		)
		(property "Footprint" ""
			(at 359.41 78.74 0)
			(effects
				(font
					(size 1.27 1.27)
					(thickness 0.15)
				)
				(justify left bottom)
				(hide yes)
			)
		)
		(property "Datasheet" ""
			(at 359.41 81.28 0)
			(effects
				(font
					(size 1.27 1.27)
					(thickness 0.15)
				)
				(justify left bottom)
				(hide yes)
			)
		)
		(property "Description" ""
			(at 344.17 71.12 0)
			(effects
				(font
					(size 1.27 1.27)
				)
				(hide yes)
			)
		)
		(property "Author" "Antmicro"
			(at 359.41 73.66 0)
			(effects
				(font
					(size 1.27 1.27)
					(thickness 0.15)
				)
				(justify left bottom)
				(hide yes)
			)
		)
		(property "License" "Apache-2.0"
			(at 359.41 76.2 0)
			(effects
				(font
					(size 1.27 1.27)
					(thickness 0.15)
				)
				(justify left bottom)
				(hide yes)
			)
		)
		(pin "1"
		)
		(instances
			(project "jetson-orin-baseboard"
				(path ""
					(reference "#PWR0319")
					(unit 1)
				)
			)
		)
	)
	(symbol
		(lib_name "GND_2")
		(lib_id "antmicropower:GND")
		(at 130.81 52.07 0)
		(unit 1)
		(exclude_from_sim no)
		(in_bom yes)
		(on_board yes)
		(dnp no)
		(property "Reference" "#PWR020"
			(at 130.81 58.42 0)
			(effects
				(font
					(size 1.27 1.27)
				)
				(justify left bottom)
				(hide yes)
			)
		)
		(property "Value" "GND"
			(at 130.81 55.88 0)
			(effects
				(font
					(size 1.27 1.27)
					(thickness 0.15)
				)
			)
		)
		(property "Footprint" ""
			(at 139.7 59.69 0)
			(effects
				(font
					(size 1.27 1.27)
					(thickness 0.15)
				)
				(justify left bottom)
				(hide yes)
			)
		)
		(property "Datasheet" ""
			(at 139.7 64.77 0)
			(effects
				(font
					(size 1.27 1.27)
					(thickness 0.15)
				)
				(justify left bottom)
				(hide yes)
			)
		)
		(property "Description" ""
			(at 130.81 52.07 0)
			(effects
				(font
					(size 1.27 1.27)
				)
				(hide yes)
			)
		)
		(property "Author" "Antmicro"
			(at 139.7 59.69 0)
			(effects
				(font
					(size 1.27 1.27)
					(thickness 0.15)
				)
				(justify left bottom)
				(hide yes)
			)
		)
		(property "License" "Apache-2.0"
			(at 139.7 62.23 0)
			(effects
				(font
					(size 1.27 1.27)
					(thickness 0.15)
				)
				(justify left bottom)
				(hide yes)
			)
		)
		(pin "1"
		)
		(instances
			(project "jetson-orin-baseboard"
				(path ""
					(reference "#PWR020")
					(unit 1)
				)
			)
		)
	)
	(symbol
		(lib_name "C_220n_0402_7")
		(lib_id "antmicroCapacitors0402:C_220n_0402")
		(at 285.75 102.87 180)
		(unit 1)
		(exclude_from_sim no)
		(in_bom yes)
		(on_board yes)
		(dnp no)
		(property "Reference" "C20"
			(at 288.29 100.965 0)
			(effects
				(font
					(size 1.27 1.27)
				)
				(justify left bottom)
			)
		)
		(property "Value" "C_220n_0402"
			(at 265.43 92.71 0)
			(effects
				(font
					(size 1.27 1.27)
					(thickness 0.15)
				)
				(justify left bottom)
				(hide yes)
			)
		)
		(property "Footprint" "antmicro-footprints:C_0402_1005Metric"
			(at 265.43 90.17 0)
			(effects
				(font
					(size 1.27 1.27)
					(thickness 0.15)
				)
				(justify left bottom)
				(hide yes)
			)
		)
		(property "Datasheet" "https://www.yageo.com/en/Chart/Download/pdf/CC0402KRX5R6BB224"
			(at 265.43 87.63 0)
			(effects
				(font
					(size 1.27 1.27)
					(thickness 0.15)
				)
				(justify left bottom)
				(hide yes)
			)
		)
		(property "Description" ""
			(at 285.75 102.87 0)
			(effects
				(font
					(size 1.27 1.27)
				)
				(hide yes)
			)
		)
		(property "Manufacturer" "YAGEO"
			(at 265.43 82.55 0)
			(effects
				(font
					(size 1.27 1.27)
					(thickness 0.15)
				)
				(justify left bottom)
				(hide yes)
			)
		)
		(property "MPN" "CC0402KRX5R6BB224"
			(at 265.43 85.09 0)
			(effects
				(font
					(size 1.27 1.27)
					(thickness 0.15)
				)
				(justify left bottom)
				(hide yes)
			)
		)
		(property "Val" "220n"
			(at 281.94 103.505 0)
			(effects
				(font
					(size 1.27 1.27)
					(thickness 0.15)
				)
				(justify left bottom)
			)
		)
		(property "License" "Apache-2.0"
			(at 265.43 80.01 0)
			(effects
				(font
					(size 1.27 1.27)
					(thickness 0.15)
				)
				(justify left bottom)
				(hide yes)
			)
		)
		(property "Author" "Antmicro"
			(at 265.43 77.47 0)
			(effects
				(font
					(size 1.27 1.27)
					(thickness 0.15)
				)
				(justify left bottom)
				(hide yes)
			)
		)
		(property "Voltage" ""
			(at 265.43 74.93 0)
			(effects
				(font
					(size 1.27 1.27)
				)
				(justify left bottom)
				(hide yes)
			)
		)
		(property "Dielectric" ""
			(at 265.43 72.39 0)
			(effects
				(font
					(size 1.27 1.27)
				)
				(justify left bottom)
				(hide yes)
			)
		)
		(pin "1"
		)
		(pin "2"
		)
		(instances
			(project "jetson-orin-baseboard"
				(path ""
					(reference "C20")
					(unit 1)
				)
			)
		)
	)
	(symbol
		(lib_name "C_10u_0603_3")
		(lib_id "antmicroCapacitors0603:C_10u_0603")
		(at 359.41 30.48 90)
		(mirror x)
		(unit 1)
		(exclude_from_sim no)
		(in_bom yes)
		(on_board yes)
		(dnp no)
		(fields_autoplaced yes)
		(property "Reference" "C22"
			(at 361.95 31.7563 90)
			(effects
				(font
					(size 1.27 1.27)
				)
				(justify right)
			)
		)
		(property "Value" "C_10u_0603"
			(at 369.57 50.8 0)
			(effects
				(font
					(size 1.27 1.27)
					(thickness 0.15)
				)
				(justify left bottom)
				(hide yes)
			)
		)
		(property "Footprint" "antmicro-footprints:C_0603_1608Metric"
			(at 372.11 50.8 0)
			(effects
				(font
					(size 1.27 1.27)
					(thickness 0.15)
				)
				(justify left bottom)
				(hide yes)
			)
		)
		(property "Datasheet" "https://www.murata.com/products/productdetail?partno=GRM188R61A106KE69%23"
			(at 374.65 50.8 0)
			(effects
				(font
					(size 1.27 1.27)
					(thickness 0.15)
				)
				(justify left bottom)
				(hide yes)
			)
		)
		(property "Description" ""
			(at 359.41 30.48 0)
			(effects
				(font
					(size 1.27 1.27)
				)
				(hide yes)
			)
		)
		(property "Manufacturer" "Murata"
			(at 379.73 50.8 0)
			(effects
				(font
					(size 1.27 1.27)
					(thickness 0.15)
				)
				(justify left bottom)
				(hide yes)
			)
		)
		(property "MPN" "GRM188R61A106KE69D"
			(at 377.19 50.8 0)
			(effects
				(font
					(size 1.27 1.27)
					(thickness 0.15)
				)
				(justify left bottom)
				(hide yes)
			)
		)
		(property "Val" "10u"
			(at 361.95 34.2963 90)
			(effects
				(font
					(size 1.27 1.27)
					(thickness 0.15)
				)
				(justify right)
			)
		)
		(property "License" "Apache-2.0"
			(at 382.27 50.8 0)
			(effects
				(font
					(size 1.27 1.27)
					(thickness 0.15)
				)
				(justify left bottom)
				(hide yes)
			)
		)
		(property "Author" "Antmicro"
			(at 384.81 50.8 0)
			(effects
				(font
					(size 1.27 1.27)
					(thickness 0.15)
				)
				(justify left bottom)
				(hide yes)
			)
		)
		(property "Voltage" ""
			(at 387.35 50.8 0)
			(effects
				(font
					(size 1.27 1.27)
				)
				(justify left bottom)
				(hide yes)
			)
		)
		(property "Dielectric" "template_dielectric"
			(at 389.89 50.8 0)
			(effects
				(font
					(size 1.27 1.27)
				)
				(justify left bottom)
				(hide yes)
			)
		)
		(pin "1"
		)
		(pin "2"
		)
		(instances
			(project "jetson-orin-baseboard"
				(path ""
					(reference "C22")
					(unit 1)
				)
			)
		)
	)
	(symbol
		(lib_name "C_10u_0603_1")
		(lib_id "antmicroCapacitors0603:C_10u_0603")
		(at 379.73 30.48 90)
		(mirror x)
		(unit 1)
		(exclude_from_sim no)
		(in_bom yes)
		(on_board yes)
		(dnp no)
		(fields_autoplaced yes)
		(property "Reference" "C24"
			(at 382.27 31.7563 90)
			(effects
				(font
					(size 1.27 1.27)
				)
				(justify right)
			)
		)
		(property "Value" "C_10u_0603"
			(at 389.89 50.8 0)
			(effects
				(font
					(size 1.27 1.27)
					(thickness 0.15)
				)
				(justify left bottom)
				(hide yes)
			)
		)
		(property "Footprint" "antmicro-footprints:C_0603_1608Metric"
			(at 392.43 50.8 0)
			(effects
				(font
					(size 1.27 1.27)
					(thickness 0.15)
				)
				(justify left bottom)
				(hide yes)
			)
		)
		(property "Datasheet" "https://www.murata.com/products/productdetail?partno=GRM188R61A106KE69%23"
			(at 394.97 50.8 0)
			(effects
				(font
					(size 1.27 1.27)
					(thickness 0.15)
				)
				(justify left bottom)
				(hide yes)
			)
		)
		(property "Description" ""
			(at 379.73 30.48 0)
			(effects
				(font
					(size 1.27 1.27)
				)
				(hide yes)
			)
		)
		(property "Manufacturer" "Murata"
			(at 400.05 50.8 0)
			(effects
				(font
					(size 1.27 1.27)
					(thickness 0.15)
				)
				(justify left bottom)
				(hide yes)
			)
		)
		(property "MPN" "GRM188R61A106KE69D"
			(at 397.51 50.8 0)
			(effects
				(font
					(size 1.27 1.27)
					(thickness 0.15)
				)
				(justify left bottom)
				(hide yes)
			)
		)
		(property "Val" "10u"
			(at 382.27 34.2963 90)
			(effects
				(font
					(size 1.27 1.27)
					(thickness 0.15)
				)
				(justify right)
			)
		)
		(property "License" "Apache-2.0"
			(at 402.59 50.8 0)
			(effects
				(font
					(size 1.27 1.27)
					(thickness 0.15)
				)
				(justify left bottom)
				(hide yes)
			)
		)
		(property "Author" "Antmicro"
			(at 405.13 50.8 0)
			(effects
				(font
					(size 1.27 1.27)
					(thickness 0.15)
				)
				(justify left bottom)
				(hide yes)
			)
		)
		(property "Voltage" ""
			(at 407.67 50.8 0)
			(effects
				(font
					(size 1.27 1.27)
				)
				(justify left bottom)
				(hide yes)
			)
		)
		(property "Dielectric" "template_dielectric"
			(at 410.21 50.8 0)
			(effects
				(font
					(size 1.27 1.27)
				)
				(justify left bottom)
				(hide yes)
			)
		)
		(pin "1"
		)
		(pin "2"
		)
		(instances
			(project "jetson-orin-baseboard"
				(path ""
					(reference "C24")
					(unit 1)
				)
			)
		)
	)
	(symbol
		(lib_name "C_10u_0603_4")
		(lib_id "antmicroCapacitors0603:C_10u_0603")
		(at 349.25 30.48 90)
		(mirror x)
		(unit 1)
		(exclude_from_sim no)
		(in_bom yes)
		(on_board yes)
		(dnp no)
		(fields_autoplaced yes)
		(property "Reference" "C21"
			(at 351.79 31.7563 90)
			(effects
				(font
					(size 1.27 1.27)
				)
				(justify right)
			)
		)
		(property "Value" "C_10u_0603"
			(at 359.41 50.8 0)
			(effects
				(font
					(size 1.27 1.27)
					(thickness 0.15)
				)
				(justify left bottom)
				(hide yes)
			)
		)
		(property "Footprint" "antmicro-footprints:C_0603_1608Metric"
			(at 361.95 50.8 0)
			(effects
				(font
					(size 1.27 1.27)
					(thickness 0.15)
				)
				(justify left bottom)
				(hide yes)
			)
		)
		(property "Datasheet" "https://www.murata.com/products/productdetail?partno=GRM188R61A106KE69%23"
			(at 364.49 50.8 0)
			(effects
				(font
					(size 1.27 1.27)
					(thickness 0.15)
				)
				(justify left bottom)
				(hide yes)
			)
		)
		(property "Description" ""
			(at 349.25 30.48 0)
			(effects
				(font
					(size 1.27 1.27)
				)
				(hide yes)
			)
		)
		(property "Manufacturer" "Murata"
			(at 369.57 50.8 0)
			(effects
				(font
					(size 1.27 1.27)
					(thickness 0.15)
				)
				(justify left bottom)
				(hide yes)
			)
		)
		(property "MPN" "GRM188R61A106KE69D"
			(at 367.03 50.8 0)
			(effects
				(font
					(size 1.27 1.27)
					(thickness 0.15)
				)
				(justify left bottom)
				(hide yes)
			)
		)
		(property "Val" "10u"
			(at 351.79 34.2963 90)
			(effects
				(font
					(size 1.27 1.27)
					(thickness 0.15)
				)
				(justify right)
			)
		)
		(property "License" "Apache-2.0"
			(at 372.11 50.8 0)
			(effects
				(font
					(size 1.27 1.27)
					(thickness 0.15)
				)
				(justify left bottom)
				(hide yes)
			)
		)
		(property "Author" "Antmicro"
			(at 374.65 50.8 0)
			(effects
				(font
					(size 1.27 1.27)
					(thickness 0.15)
				)
				(justify left bottom)
				(hide yes)
			)
		)
		(property "Voltage" ""
			(at 377.19 50.8 0)
			(effects
				(font
					(size 1.27 1.27)
				)
				(justify left bottom)
				(hide yes)
			)
		)
		(property "Dielectric" "template_dielectric"
			(at 379.73 50.8 0)
			(effects
				(font
					(size 1.27 1.27)
				)
				(justify left bottom)
				(hide yes)
			)
		)
		(pin "1"
		)
		(pin "2"
		)
		(instances
			(project "jetson-orin-baseboard"
				(path ""
					(reference "C21")
					(unit 1)
				)
			)
		)
	)
	(symbol
		(lib_id "antmicropower:GND")
		(at 223.52 267.97 0)
		(unit 1)
		(exclude_from_sim no)
		(in_bom yes)
		(on_board yes)
		(dnp no)
		(property "Reference" "#PWR028"
			(at 223.52 274.32 0)
			(effects
				(font
					(size 1.27 1.27)
				)
				(justify left bottom)
				(hide yes)
			)
		)
		(property "Value" "GND"
			(at 221.615 271.78 0)
			(effects
				(font
					(size 1.27 1.27)
					(thickness 0.15)
				)
				(justify left)
			)
		)
		(property "Footprint" ""
			(at 232.41 275.59 0)
			(effects
				(font
					(size 1.27 1.27)
					(thickness 0.15)
				)
				(justify left bottom)
				(hide yes)
			)
		)
		(property "Datasheet" ""
			(at 232.41 280.67 0)
			(effects
				(font
					(size 1.27 1.27)
					(thickness 0.15)
				)
				(justify left bottom)
				(hide yes)
			)
		)
		(property "Description" ""
			(at 223.52 267.97 0)
			(effects
				(font
					(size 1.27 1.27)
				)
				(hide yes)
			)
		)
		(property "Author" "Antmicro"
			(at 232.41 275.59 0)
			(effects
				(font
					(size 1.27 1.27)
					(thickness 0.15)
				)
				(justify left bottom)
				(hide yes)
			)
		)
		(property "License" "Apache-2.0"
			(at 232.41 278.13 0)
			(effects
				(font
					(size 1.27 1.27)
					(thickness 0.15)
				)
				(justify left bottom)
				(hide yes)
			)
		)
		(pin "1"
		)
		(instances
			(project "jetson-orin-baseboard"
				(path ""
					(reference "#PWR028")
					(unit 1)
				)
			)
		)
	)
	(symbol
		(lib_id "antmicroResistors0603:R_0R_22.4A_0603")
		(at 379.73 25.4 90)
		(unit 1)
		(exclude_from_sim no)
		(in_bom yes)
		(on_board yes)
		(dnp no)
		(property "Reference" "R143"
			(at 382.27 20.32 90)
			(effects
				(font
					(size 1.27 1.27)
				)
				(justify right)
			)
		)
		(property "Value" "R_0R_22.4A_0603"
			(at 382.27 21.59 90)
			(effects
				(font
					(size 1.27 1.27)
					(thickness 0.15)
				)
				(justify right)
				(hide yes)
			)
		)
		(property "Footprint" "antmicro-footprints:R_0603_1608Metric"
			(at 389.89 10.16 0)
			(effects
				(font
					(size 1.27 1.27)
					(thickness 0.15)
				)
				(justify left bottom)
				(hide yes)
			)
		)
		(property "Datasheet" "https://fscdn.rohm.com/en/products/databook/datasheet/passive/resistor/chip_resistor/pmr-jpw-e.pdf"
			(at 392.43 10.16 0)
			(effects
				(font
					(size 1.27 1.27)
					(thickness 0.15)
				)
				(justify left bottom)
				(hide yes)
			)
		)
		(property "Description" ""
			(at 379.73 25.4 0)
			(effects
				(font
					(size 1.27 1.27)
				)
				(hide yes)
			)
		)
		(property "Manufacturer" "ROHM Semiconductor"
			(at 397.51 10.16 0)
			(effects
				(font
					(size 1.27 1.27)
					(thickness 0.15)
				)
				(justify left bottom)
				(hide yes)
			)
		)
		(property "MPN" "PMR03EZPJ000"
			(at 394.97 10.16 0)
			(effects
				(font
					(size 1.27 1.27)
					(thickness 0.15)
				)
				(justify left bottom)
				(hide yes)
			)
		)
		(property "Val" "0R"
			(at 382.27 22.86 90)
			(effects
				(font
					(size 1.27 1.27)
					(thickness 0.15)
				)
				(justify right)
			)
		)
		(property "Author" "Antmicro"
			(at 402.59 10.16 0)
			(effects
				(font
					(size 1.27 1.27)
					(thickness 0.15)
				)
				(justify left bottom)
				(hide yes)
			)
		)
		(property "License" "Apache-2.0"
			(at 405.13 10.16 0)
			(effects
				(font
					(size 1.27 1.27)
					(thickness 0.15)
				)
				(justify left bottom)
				(hide yes)
			)
		)
		(property "Max. Curr." "22.4A"
			(at 382.27 25.4 90)
			(effects
				(font
					(size 1.27 1.27)
					(thickness 0.15)
				)
				(justify right)
			)
		)
		(property "Tolerance" "template_tolerance"
			(at 389.89 5.08 0)
			(effects
				(font
					(size 1.27 1.27)
				)
				(justify left bottom)
				(hide yes)
			)
		)
		(pin "1"
		)
		(pin "2"
		)
		(instances
			(project "jetson-orin-baseboard"
				(path ""
					(reference "R143")
					(unit 1)
				)
			)
		)
	)
	(symbol
		(lib_name "TP_0.75mm_SMD_1")
		(lib_id "antmicroTestPoints:TP_0.75mm_SMD")
		(at 359.41 59.69 0)
		(unit 1)
		(exclude_from_sim no)
		(in_bom no)
		(on_board yes)
		(dnp no)
		(property "Reference" "TP10"
			(at 363.22 59.69 0)
			(effects
				(font
					(size 1.27 1.27)
				)
				(justify left)
			)
		)
		(property "Value" "TP_0.75mm_SMD"
			(at 369.57 63.5 0)
			(effects
				(font
					(size 1.27 1.27)
					(thickness 0.15)
				)
				(justify left bottom)
				(hide yes)
			)
		)
		(property "Footprint" "antmicro-footprints:TP_SMD_0.75mm"
			(at 369.57 66.04 0)
			(effects
				(font
					(size 1.27 1.27)
					(thickness 0.15)
				)
				(justify left bottom)
				(hide yes)
			)
		)
		(property "Datasheet" ""
			(at 377.19 72.39 0)
			(effects
				(font
					(size 1.27 1.27)
					(thickness 0.15)
				)
				(justify left bottom)
				(hide yes)
			)
		)
		(property "Description" ""
			(at 359.41 59.69 0)
			(effects
				(font
					(size 1.27 1.27)
				)
				(hide yes)
			)
		)
		(property "MPN" ""
			(at 370.205 71.12 0)
			(effects
				(font
					(size 1.27 1.27)
					(thickness 0.15)
				)
				(justify left bottom)
				(hide yes)
			)
		)
		(property "Manufacturer" ""
			(at 370.205 66.04 0)
			(effects
				(font
					(size 1.27 1.27)
					(thickness 0.15)
				)
				(justify left bottom)
				(hide yes)
			)
		)
		(property "Author" "Antmicro"
			(at 369.57 68.58 0)
			(effects
				(font
					(size 1.27 1.27)
					(thickness 0.15)
				)
				(justify left bottom)
				(hide yes)
			)
		)
		(property "License" "Apache-2.0"
			(at 369.57 71.12 0)
			(effects
				(font
					(size 1.27 1.27)
					(thickness 0.15)
				)
				(justify left bottom)
				(hide yes)
			)
		)
		(pin "1"
		)
		(instances
			(project "jetson-orin-baseboard"
				(path ""
					(reference "TP10")
					(unit 1)
				)
			)
		)
	)
	(symbol
		(lib_id "antmicroPciConnectors:Bus_M.2_1-2199230-6")
		(at 312.42 33.02 0)
		(unit 1)
		(exclude_from_sim no)
		(in_bom yes)
		(on_board yes)
		(dnp no)
		(fields_autoplaced yes)
		(property "Reference" "J2"
			(at 327.66 25.4 0)
			(effects
				(font
					(size 1.27 1.27)
					(thickness 0.15)
				)
			)
		)
		(property "Value" "Bus_M.2_1-2199230-6"
			(at 358.14 40.64 0)
			(effects
				(font
					(size 1.27 1.27)
					(thickness 0.15)
				)
				(justify left bottom)
				(hide yes)
			)
		)
		(property "Footprint" "antmicro-footprints:Bus_M.2_Socket_Key_M_TE_1-2199230-6"
			(at 358.14 43.18 0)
			(effects
				(font
					(size 1.27 1.27)
					(thickness 0.15)
				)
				(justify left bottom)
				(hide yes)
			)
		)
		(property "Datasheet" "https://www.te.com/commerce/DocumentDelivery/DDEController?Action=srchrtrv&DocNm=2199230&DocType=Customer+Drawing&DocLang=English"
			(at 358.14 45.72 0)
			(effects
				(font
					(size 1.27 1.27)
					(thickness 0.15)
				)
				(justify left bottom)
				(hide yes)
			)
		)
		(property "Description" ""
			(at 312.42 33.02 0)
			(effects
				(font
					(size 1.27 1.27)
				)
				(hide yes)
			)
		)
		(property "Manufacturer" "TE Connectivity"
			(at 358.14 48.26 0)
			(effects
				(font
					(size 1.27 1.27)
					(thickness 0.15)
				)
				(justify left bottom)
				(hide yes)
			)
		)
		(property "MPN" "1-2199230-6"
			(at 327.66 27.94 0)
			(effects
				(font
					(size 1.27 1.27)
					(thickness 0.15)
				)
			)
		)
		(property "Author" "Antmicro"
			(at 358.14 50.8 0)
			(effects
				(font
					(size 1.27 1.27)
					(thickness 0.15)
				)
				(justify left bottom)
				(hide yes)
			)
		)
		(property "License" "Apache-2.0"
			(at 358.14 53.34 0)
			(effects
				(font
					(size 1.27 1.27)
					(thickness 0.15)
				)
				(justify left bottom)
				(hide yes)
			)
		)
		(pin "1"
		)
		(pin "10"
		)
		(pin "11"
		)
		(pin "12"
		)
		(pin "13"
		)
		(pin "14"
		)
		(pin "15"
		)
		(pin "16"
		)
		(pin "17"
		)
		(pin "18"
		)
		(pin "19"
		)
		(pin "2"
		)
		(pin "20"
		)
		(pin "21"
		)
		(pin "22"
		)
		(pin "23"
		)
		(pin "24"
		)
		(pin "25"
		)
		(pin "26"
		)
		(pin "27"
		)
		(pin "28"
		)
		(pin "29"
		)
		(pin "3"
		)
		(pin "30"
		)
		(pin "31"
		)
		(pin "32"
		)
		(pin "33"
		)
		(pin "34"
		)
		(pin "35"
		)
		(pin "36"
		)
		(pin "37"
		)
		(pin "38"
		)
		(pin "39"
		)
		(pin "4"
		)
		(pin "40"
		)
		(pin "41"
		)
		(pin "42"
		)
		(pin "43"
		)
		(pin "44"
		)
		(pin "45"
		)
		(pin "46"
		)
		(pin "47"
		)
		(pin "48"
		)
		(pin "49"
		)
		(pin "5"
		)
		(pin "50"
		)
		(pin "51"
		)
		(pin "52"
		)
		(pin "53"
		)
		(pin "54"
		)
		(pin "55"
		)
		(pin "56"
		)
		(pin "57"
		)
		(pin "58"
		)
		(pin "6"
		)
		(pin "67"
		)
		(pin "68"
		)
		(pin "69"
		)
		(pin "7"
		)
		(pin "70"
		)
		(pin "71"
		)
		(pin "72"
		)
		(pin "73"
		)
		(pin "74"
		)
		(pin "75"
		)
		(pin "8"
		)
		(pin "9"
		)
		(pin "MP1"
		)
		(pin "MP2"
		)
		(instances
			(project "jetson-orin-baseboard"
				(path ""
					(reference "J2")
					(unit 1)
				)
			)
		)
	)
	(symbol
		(lib_name "R_0R_0402_5")
		(lib_id "antmicroResistors0402:R_0R_0402")
		(at 62.23 104.14 0)
		(unit 1)
		(exclude_from_sim no)
		(in_bom yes)
		(on_board yes)
		(dnp no)
		(property "Reference" "R14"
			(at 67.31 103.505 0)
			(effects
				(font
					(size 1.27 1.27)
				)
				(justify left bottom)
			)
		)
		(property "Value" "R_0R_0402"
			(at 82.55 116.84 0)
			(effects
				(font
					(size 1.27 1.27)
					(thickness 0.15)
				)
				(justify left bottom)
				(hide yes)
			)
		)
		(property "Footprint" "antmicro-footprints:R_0402_1005Metric"
			(at 82.55 119.38 0)
			(effects
				(font
					(size 1.27 1.27)
					(thickness 0.15)
				)
				(justify left bottom)
				(hide yes)
			)
		)
		(property "Datasheet" "https://industrial.panasonic.com/cdbs/www-data/pdf/RDA0000/AOA0000C301.pdf"
			(at 82.55 121.92 0)
			(effects
				(font
					(size 1.27 1.27)
					(thickness 0.15)
				)
				(justify left bottom)
				(hide yes)
			)
		)
		(property "Description" ""
			(at 62.23 104.14 0)
			(effects
				(font
					(size 1.27 1.27)
				)
				(hide yes)
			)
		)
		(property "Manufacturer" "Panasonic"
			(at 82.55 127 0)
			(effects
				(font
					(size 1.27 1.27)
					(thickness 0.15)
				)
				(justify left bottom)
				(hide yes)
			)
		)
		(property "MPN" "ERJ2GE0R00X"
			(at 82.55 124.46 0)
			(effects
				(font
					(size 1.27 1.27)
					(thickness 0.15)
				)
				(justify left bottom)
				(hide yes)
			)
		)
		(property "Val" "0R"
			(at 59.69 103.505 0)
			(effects
				(font
					(size 1.27 1.27)
					(thickness 0.15)
				)
				(justify left bottom)
			)
		)
		(property "License" "Apache-2.0"
			(at 82.55 129.54 0)
			(effects
				(font
					(size 1.27 1.27)
					(thickness 0.15)
				)
				(justify left bottom)
				(hide yes)
			)
		)
		(property "Author" "Antmicro"
			(at 82.55 132.08 0)
			(effects
				(font
					(size 1.27 1.27)
					(thickness 0.15)
				)
				(justify left bottom)
				(hide yes)
			)
		)
		(property "Tolerance" "~"
			(at 82.55 114.3 0)
			(effects
				(font
					(size 1.27 1.27)
				)
				(justify left bottom)
				(hide yes)
			)
		)
		(property "Current" "1A"
			(at 82.55 134.62 0)
			(effects
				(font
					(size 1.27 1.27)
					(thickness 0.15)
				)
				(justify left bottom)
				(hide yes)
			)
		)
		(pin "1"
		)
		(pin "2"
		)
		(instances
			(project "jetson-orin-baseboard"
				(path ""
					(reference "R14")
					(unit 1)
				)
			)
		)
	)
	(symbol
		(lib_name "R_0R_0402_2")
		(lib_id "antmicroResistors0402:R_0R_0402")
		(at 64.77 46.99 0)
		(unit 1)
		(exclude_from_sim no)
		(in_bom yes)
		(on_board yes)
		(dnp no)
		(property "Reference" "R19"
			(at 69.85 46.355 0)
			(effects
				(font
					(size 1.27 1.27)
				)
				(justify left bottom)
			)
		)
		(property "Value" "R_0R_0402"
			(at 85.09 59.69 0)
			(effects
				(font
					(size 1.27 1.27)
					(thickness 0.15)
				)
				(justify left bottom)
				(hide yes)
			)
		)
		(property "Footprint" "antmicro-footprints:R_0402_1005Metric"
			(at 85.09 62.23 0)
			(effects
				(font
					(size 1.27 1.27)
					(thickness 0.15)
				)
				(justify left bottom)
				(hide yes)
			)
		)
		(property "Datasheet" "https://industrial.panasonic.com/cdbs/www-data/pdf/RDA0000/AOA0000C301.pdf"
			(at 85.09 64.77 0)
			(effects
				(font
					(size 1.27 1.27)
					(thickness 0.15)
				)
				(justify left bottom)
				(hide yes)
			)
		)
		(property "Description" ""
			(at 64.77 46.99 0)
			(effects
				(font
					(size 1.27 1.27)
				)
				(hide yes)
			)
		)
		(property "Manufacturer" "Panasonic"
			(at 85.09 69.85 0)
			(effects
				(font
					(size 1.27 1.27)
					(thickness 0.15)
				)
				(justify left bottom)
				(hide yes)
			)
		)
		(property "MPN" "ERJ2GE0R00X"
			(at 85.09 67.31 0)
			(effects
				(font
					(size 1.27 1.27)
					(thickness 0.15)
				)
				(justify left bottom)
				(hide yes)
			)
		)
		(property "Val" "0R"
			(at 62.23 46.355 0)
			(effects
				(font
					(size 1.27 1.27)
					(thickness 0.15)
				)
				(justify left bottom)
			)
		)
		(property "License" "Apache-2.0"
			(at 85.09 72.39 0)
			(effects
				(font
					(size 1.27 1.27)
					(thickness 0.15)
				)
				(justify left bottom)
				(hide yes)
			)
		)
		(property "Author" "Antmicro"
			(at 85.09 74.93 0)
			(effects
				(font
					(size 1.27 1.27)
					(thickness 0.15)
				)
				(justify left bottom)
				(hide yes)
			)
		)
		(property "Tolerance" "~"
			(at 85.09 57.15 0)
			(effects
				(font
					(size 1.27 1.27)
				)
				(justify left bottom)
				(hide yes)
			)
		)
		(property "Current" "1A"
			(at 85.09 77.47 0)
			(effects
				(font
					(size 1.27 1.27)
					(thickness 0.15)
				)
				(justify left bottom)
				(hide yes)
			)
		)
		(pin "1"
		)
		(pin "2"
		)
		(instances
			(project "jetson-orin-baseboard"
				(path ""
					(reference "R19")
					(unit 1)
				)
			)
		)
	)
	(symbol
		(lib_name "C_220n_0402_5")
		(lib_id "antmicroCapacitors0402:C_220n_0402")
		(at 287.02 87.63 180)
		(unit 1)
		(exclude_from_sim no)
		(in_bom yes)
		(on_board yes)
		(dnp no)
		(property "Reference" "C19"
			(at 289.56 85.725 0)
			(effects
				(font
					(size 1.27 1.27)
				)
				(justify left bottom)
			)
		)
		(property "Value" "C_220n_0402"
			(at 266.7 77.47 0)
			(effects
				(font
					(size 1.27 1.27)
					(thickness 0.15)
				)
				(justify left bottom)
				(hide yes)
			)
		)
		(property "Footprint" "antmicro-footprints:C_0402_1005Metric"
			(at 266.7 74.93 0)
			(effects
				(font
					(size 1.27 1.27)
					(thickness 0.15)
				)
				(justify left bottom)
				(hide yes)
			)
		)
		(property "Datasheet" "https://www.yageo.com/en/Chart/Download/pdf/CC0402KRX5R6BB224"
			(at 266.7 72.39 0)
			(effects
				(font
					(size 1.27 1.27)
					(thickness 0.15)
				)
				(justify left bottom)
				(hide yes)
			)
		)
		(property "Description" ""
			(at 287.02 87.63 0)
			(effects
				(font
					(size 1.27 1.27)
				)
				(hide yes)
			)
		)
		(property "Manufacturer" "YAGEO"
			(at 266.7 67.31 0)
			(effects
				(font
					(size 1.27 1.27)
					(thickness 0.15)
				)
				(justify left bottom)
				(hide yes)
			)
		)
		(property "MPN" "CC0402KRX5R6BB224"
			(at 266.7 69.85 0)
			(effects
				(font
					(size 1.27 1.27)
					(thickness 0.15)
				)
				(justify left bottom)
				(hide yes)
			)
		)
		(property "Val" "220n"
			(at 283.21 88.265 0)
			(effects
				(font
					(size 1.27 1.27)
					(thickness 0.15)
				)
				(justify left bottom)
			)
		)
		(property "License" "Apache-2.0"
			(at 266.7 64.77 0)
			(effects
				(font
					(size 1.27 1.27)
					(thickness 0.15)
				)
				(justify left bottom)
				(hide yes)
			)
		)
		(property "Author" "Antmicro"
			(at 266.7 62.23 0)
			(effects
				(font
					(size 1.27 1.27)
					(thickness 0.15)
				)
				(justify left bottom)
				(hide yes)
			)
		)
		(property "Voltage" ""
			(at 266.7 59.69 0)
			(effects
				(font
					(size 1.27 1.27)
				)
				(justify left bottom)
				(hide yes)
			)
		)
		(property "Dielectric" ""
			(at 266.7 57.15 0)
			(effects
				(font
					(size 1.27 1.27)
				)
				(justify left bottom)
				(hide yes)
			)
		)
		(pin "1"
		)
		(pin "2"
		)
		(instances
			(project "jetson-orin-baseboard"
				(path ""
					(reference "C19")
					(unit 1)
				)
			)
		)
	)
	(symbol
		(lib_name "R_0R_0402_6")
		(lib_id "antmicroResistors0402:R_0R_0402")
		(at 62.23 99.06 0)
		(unit 1)
		(exclude_from_sim no)
		(in_bom yes)
		(on_board yes)
		(dnp no)
		(property "Reference" "R13"
			(at 67.31 98.425 0)
			(effects
				(font
					(size 1.27 1.27)
				)
				(justify left bottom)
			)
		)
		(property "Value" "R_0R_0402"
			(at 82.55 111.76 0)
			(effects
				(font
					(size 1.27 1.27)
					(thickness 0.15)
				)
				(justify left bottom)
				(hide yes)
			)
		)
		(property "Footprint" "antmicro-footprints:R_0402_1005Metric"
			(at 82.55 114.3 0)
			(effects
				(font
					(size 1.27 1.27)
					(thickness 0.15)
				)
				(justify left bottom)
				(hide yes)
			)
		)
		(property "Datasheet" "https://industrial.panasonic.com/cdbs/www-data/pdf/RDA0000/AOA0000C301.pdf"
			(at 82.55 116.84 0)
			(effects
				(font
					(size 1.27 1.27)
					(thickness 0.15)
				)
				(justify left bottom)
				(hide yes)
			)
		)
		(property "Description" ""
			(at 62.23 99.06 0)
			(effects
				(font
					(size 1.27 1.27)
				)
				(hide yes)
			)
		)
		(property "Manufacturer" "Panasonic"
			(at 82.55 121.92 0)
			(effects
				(font
					(size 1.27 1.27)
					(thickness 0.15)
				)
				(justify left bottom)
				(hide yes)
			)
		)
		(property "MPN" "ERJ2GE0R00X"
			(at 82.55 119.38 0)
			(effects
				(font
					(size 1.27 1.27)
					(thickness 0.15)
				)
				(justify left bottom)
				(hide yes)
			)
		)
		(property "Val" "0R"
			(at 59.69 98.425 0)
			(effects
				(font
					(size 1.27 1.27)
					(thickness 0.15)
				)
				(justify left bottom)
			)
		)
		(property "License" "Apache-2.0"
			(at 82.55 124.46 0)
			(effects
				(font
					(size 1.27 1.27)
					(thickness 0.15)
				)
				(justify left bottom)
				(hide yes)
			)
		)
		(property "Author" "Antmicro"
			(at 82.55 127 0)
			(effects
				(font
					(size 1.27 1.27)
					(thickness 0.15)
				)
				(justify left bottom)
				(hide yes)
			)
		)
		(property "Tolerance" "~"
			(at 82.55 109.22 0)
			(effects
				(font
					(size 1.27 1.27)
				)
				(justify left bottom)
				(hide yes)
			)
		)
		(property "Current" "1A"
			(at 82.55 129.54 0)
			(effects
				(font
					(size 1.27 1.27)
					(thickness 0.15)
				)
				(justify left bottom)
				(hide yes)
			)
		)
		(pin "1"
		)
		(pin "2"
		)
		(instances
			(project "jetson-orin-baseboard"
				(path ""
					(reference "R13")
					(unit 1)
				)
			)
		)
	)
	(symbol
		(lib_id "antmicroTestPoints:TP_0.75mm_SMD")
		(at 264.16 203.2 0)
		(unit 1)
		(exclude_from_sim no)
		(in_bom no)
		(on_board yes)
		(dnp no)
		(property "Reference" "TP9"
			(at 268.605 204.47 0)
			(effects
				(font
					(size 1.27 1.27)
				)
				(justify left bottom)
			)
		)
		(property "Value" "TP_0.75mm_SMD"
			(at 274.32 207.01 0)
			(effects
				(font
					(size 1.27 1.27)
					(thickness 0.15)
				)
				(justify left bottom)
				(hide yes)
			)
		)
		(property "Footprint" "antmicro-footprints:TP_SMD_0.75mm"
			(at 274.32 209.55 0)
			(effects
				(font
					(size 1.27 1.27)
					(thickness 0.15)
				)
				(justify left bottom)
				(hide yes)
			)
		)
		(property "Datasheet" ""
			(at 281.94 215.9 0)
			(effects
				(font
					(size 1.27 1.27)
					(thickness 0.15)
				)
				(justify left bottom)
				(hide yes)
			)
		)
		(property "Description" ""
			(at 264.16 203.2 0)
			(effects
				(font
					(size 1.27 1.27)
				)
				(hide yes)
			)
		)
		(property "MPN" ""
			(at 274.955 214.63 0)
			(effects
				(font
					(size 1.27 1.27)
					(thickness 0.15)
				)
				(justify left bottom)
				(hide yes)
			)
		)
		(property "Manufacturer" ""
			(at 274.955 209.55 0)
			(effects
				(font
					(size 1.27 1.27)
					(thickness 0.15)
				)
				(justify left bottom)
				(hide yes)
			)
		)
		(property "Author" "Antmicro"
			(at 274.32 212.09 0)
			(effects
				(font
					(size 1.27 1.27)
					(thickness 0.15)
				)
				(justify left bottom)
				(hide yes)
			)
		)
		(property "License" "Apache-2.0"
			(at 274.32 214.63 0)
			(effects
				(font
					(size 1.27 1.27)
					(thickness 0.15)
				)
				(justify left bottom)
				(hide yes)
			)
		)
		(pin "1"
		)
		(instances
			(project "jetson-orin-baseboard"
				(path ""
					(reference "TP9")
					(unit 1)
				)
			)
		)
	)
	(symbol
		(lib_name "TP_0.75mm_SMD_2")
		(lib_id "antmicroTestPoints:TP_0.75mm_SMD")
		(at 359.41 62.23 0)
		(unit 1)
		(exclude_from_sim no)
		(in_bom no)
		(on_board yes)
		(dnp no)
		(property "Reference" "TP11"
			(at 363.22 62.23 0)
			(effects
				(font
					(size 1.27 1.27)
				)
				(justify left)
			)
		)
		(property "Value" "TP_0.75mm_SMD"
			(at 369.57 66.04 0)
			(effects
				(font
					(size 1.27 1.27)
					(thickness 0.15)
				)
				(justify left bottom)
				(hide yes)
			)
		)
		(property "Footprint" "antmicro-footprints:TP_SMD_0.75mm"
			(at 369.57 68.58 0)
			(effects
				(font
					(size 1.27 1.27)
					(thickness 0.15)
				)
				(justify left bottom)
				(hide yes)
			)
		)
		(property "Datasheet" ""
			(at 377.19 74.93 0)
			(effects
				(font
					(size 1.27 1.27)
					(thickness 0.15)
				)
				(justify left bottom)
				(hide yes)
			)
		)
		(property "Description" ""
			(at 359.41 62.23 0)
			(effects
				(font
					(size 1.27 1.27)
				)
				(hide yes)
			)
		)
		(property "MPN" ""
			(at 370.205 73.66 0)
			(effects
				(font
					(size 1.27 1.27)
					(thickness 0.15)
				)
				(justify left bottom)
				(hide yes)
			)
		)
		(property "Manufacturer" ""
			(at 370.205 68.58 0)
			(effects
				(font
					(size 1.27 1.27)
					(thickness 0.15)
				)
				(justify left bottom)
				(hide yes)
			)
		)
		(property "Author" "Antmicro"
			(at 369.57 71.12 0)
			(effects
				(font
					(size 1.27 1.27)
					(thickness 0.15)
				)
				(justify left bottom)
				(hide yes)
			)
		)
		(property "License" "Apache-2.0"
			(at 369.57 73.66 0)
			(effects
				(font
					(size 1.27 1.27)
					(thickness 0.15)
				)
				(justify left bottom)
				(hide yes)
			)
		)
		(pin "1"
		)
		(instances
			(project "jetson-orin-baseboard"
				(path ""
					(reference "TP11")
					(unit 1)
				)
			)
		)
	)
	(symbol
		(lib_id "antmicropower:GND")
		(at 255.27 158.75 0)
		(unit 1)
		(exclude_from_sim no)
		(in_bom yes)
		(on_board yes)
		(dnp no)
		(property "Reference" "#PWR030"
			(at 255.27 165.1 0)
			(effects
				(font
					(size 1.27 1.27)
				)
				(justify left bottom)
				(hide yes)
			)
		)
		(property "Value" "GND"
			(at 253.365 162.56 0)
			(effects
				(font
					(size 1.27 1.27)
					(thickness 0.15)
				)
				(justify left)
			)
		)
		(property "Footprint" ""
			(at 264.16 166.37 0)
			(effects
				(font
					(size 1.27 1.27)
					(thickness 0.15)
				)
				(justify left bottom)
				(hide yes)
			)
		)
		(property "Datasheet" ""
			(at 264.16 171.45 0)
			(effects
				(font
					(size 1.27 1.27)
					(thickness 0.15)
				)
				(justify left bottom)
				(hide yes)
			)
		)
		(property "Description" ""
			(at 255.27 158.75 0)
			(effects
				(font
					(size 1.27 1.27)
				)
				(hide yes)
			)
		)
		(property "Author" "Antmicro"
			(at 264.16 166.37 0)
			(effects
				(font
					(size 1.27 1.27)
					(thickness 0.15)
				)
				(justify left bottom)
				(hide yes)
			)
		)
		(property "License" "Apache-2.0"
			(at 264.16 168.91 0)
			(effects
				(font
					(size 1.27 1.27)
					(thickness 0.15)
				)
				(justify left bottom)
				(hide yes)
			)
		)
		(pin "1"
		)
		(instances
			(project "jetson-orin-baseboard"
				(path ""
					(reference "#PWR030")
					(unit 1)
				)
			)
		)
	)
	(symbol
		(lib_name "+3V3_1")
		(lib_id "antmicropower:+3V3")
		(at 168.91 80.01 0)
		(unit 1)
		(exclude_from_sim no)
		(in_bom yes)
		(on_board yes)
		(dnp no)
		(property "Reference" "#PWR025"
			(at 168.91 83.82 0)
			(effects
				(font
					(size 1.27 1.27)
				)
				(justify left bottom)
				(hide yes)
			)
		)
		(property "Value" "+3V3"
			(at 168.275 76.2 0)
			(effects
				(font
					(size 1.27 1.27)
					(thickness 0.15)
				)
			)
		)
		(property "Footprint" ""
			(at 184.15 87.63 0)
			(effects
				(font
					(size 1.27 1.27)
					(thickness 0.15)
				)
				(justify left bottom)
				(hide yes)
			)
		)
		(property "Datasheet" ""
			(at 184.15 90.17 0)
			(effects
				(font
					(size 1.27 1.27)
					(thickness 0.15)
				)
				(justify left bottom)
				(hide yes)
			)
		)
		(property "Description" ""
			(at 168.91 80.01 0)
			(effects
				(font
					(size 1.27 1.27)
				)
				(hide yes)
			)
		)
		(property "Author" "Antmicro"
			(at 184.15 82.55 0)
			(effects
				(font
					(size 1.27 1.27)
					(thickness 0.15)
				)
				(justify left bottom)
				(hide yes)
			)
		)
		(property "License" "Apache-2.0"
			(at 184.15 85.09 0)
			(effects
				(font
					(size 1.27 1.27)
					(thickness 0.15)
				)
				(justify left bottom)
				(hide yes)
			)
		)
		(pin "1"
		)
		(instances
			(project "jetson-orin-baseboard"
				(path ""
					(reference "#PWR025")
					(unit 1)
				)
			)
		)
	)
	(symbol
		(lib_id "antmicroTestPoints:TP_0.75mm_SMD")
		(at 264.16 195.58 0)
		(unit 1)
		(exclude_from_sim no)
		(in_bom no)
		(on_board yes)
		(dnp no)
		(property "Reference" "TP7"
			(at 267.97 196.215 0)
			(effects
				(font
					(size 1.27 1.27)
				)
				(justify left bottom)
			)
		)
		(property "Value" "TP_0.75mm_SMD"
			(at 274.32 199.39 0)
			(effects
				(font
					(size 1.27 1.27)
					(thickness 0.15)
				)
				(justify left bottom)
				(hide yes)
			)
		)
		(property "Footprint" "antmicro-footprints:TP_SMD_0.75mm"
			(at 274.32 201.93 0)
			(effects
				(font
					(size 1.27 1.27)
					(thickness 0.15)
				)
				(justify left bottom)
				(hide yes)
			)
		)
		(property "Datasheet" ""
			(at 281.94 208.28 0)
			(effects
				(font
					(size 1.27 1.27)
					(thickness 0.15)
				)
				(justify left bottom)
				(hide yes)
			)
		)
		(property "Description" ""
			(at 264.16 195.58 0)
			(effects
				(font
					(size 1.27 1.27)
				)
				(hide yes)
			)
		)
		(property "MPN" ""
			(at 274.955 207.01 0)
			(effects
				(font
					(size 1.27 1.27)
					(thickness 0.15)
				)
				(justify left bottom)
				(hide yes)
			)
		)
		(property "Manufacturer" ""
			(at 274.955 201.93 0)
			(effects
				(font
					(size 1.27 1.27)
					(thickness 0.15)
				)
				(justify left bottom)
				(hide yes)
			)
		)
		(property "Author" "Antmicro"
			(at 274.32 204.47 0)
			(effects
				(font
					(size 1.27 1.27)
					(thickness 0.15)
				)
				(justify left bottom)
				(hide yes)
			)
		)
		(property "License" "Apache-2.0"
			(at 274.32 207.01 0)
			(effects
				(font
					(size 1.27 1.27)
					(thickness 0.15)
				)
				(justify left bottom)
				(hide yes)
			)
		)
		(pin "1"
		)
		(instances
			(project "jetson-orin-baseboard"
				(path ""
					(reference "TP7")
					(unit 1)
				)
			)
		)
	)
	(symbol
		(lib_name "GND_5")
		(lib_id "antmicropower:GND")
		(at 359.41 35.56 0)
		(unit 1)
		(exclude_from_sim no)
		(in_bom yes)
		(on_board yes)
		(dnp no)
		(property "Reference" "#PWR038"
			(at 359.41 41.91 0)
			(effects
				(font
					(size 1.27 1.27)
				)
				(justify left bottom)
				(hide yes)
			)
		)
		(property "Value" "GND"
			(at 357.505 40.005 0)
			(effects
				(font
					(size 1.27 1.27)
					(thickness 0.15)
				)
				(justify left bottom)
			)
		)
		(property "Footprint" ""
			(at 368.3 43.18 0)
			(effects
				(font
					(size 1.27 1.27)
					(thickness 0.15)
				)
				(justify left bottom)
				(hide yes)
			)
		)
		(property "Datasheet" ""
			(at 368.3 48.26 0)
			(effects
				(font
					(size 1.27 1.27)
					(thickness 0.15)
				)
				(justify left bottom)
				(hide yes)
			)
		)
		(property "Description" ""
			(at 359.41 35.56 0)
			(effects
				(font
					(size 1.27 1.27)
				)
				(hide yes)
			)
		)
		(property "Author" "Antmicro"
			(at 368.3 43.18 0)
			(effects
				(font
					(size 1.27 1.27)
					(thickness 0.15)
				)
				(justify left bottom)
				(hide yes)
			)
		)
		(property "License" "Apache-2.0"
			(at 368.3 45.72 0)
			(effects
				(font
					(size 1.27 1.27)
					(thickness 0.15)
				)
				(justify left bottom)
				(hide yes)
			)
		)
		(pin "1"
		)
		(instances
			(project "jetson-orin-baseboard"
				(path ""
					(reference "#PWR038")
					(unit 1)
				)
			)
		)
	)
	(symbol
		(lib_id "antmicropower:+3V3")
		(at 175.26 151.13 0)
		(unit 1)
		(exclude_from_sim no)
		(in_bom yes)
		(on_board yes)
		(dnp no)
		(property "Reference" "#PWR027"
			(at 175.26 154.94 0)
			(effects
				(font
					(size 1.27 1.27)
				)
				(justify left bottom)
				(hide yes)
			)
		)
		(property "Value" "+3V3"
			(at 172.085 147.32 0)
			(effects
				(font
					(size 1.27 1.27)
					(thickness 0.15)
				)
				(justify left)
			)
		)
		(property "Footprint" ""
			(at 190.5 158.75 0)
			(effects
				(font
					(size 1.27 1.27)
					(thickness 0.15)
				)
				(justify left bottom)
				(hide yes)
			)
		)
		(property "Datasheet" ""
			(at 190.5 161.29 0)
			(effects
				(font
					(size 1.27 1.27)
					(thickness 0.15)
				)
				(justify left bottom)
				(hide yes)
			)
		)
		(property "Description" ""
			(at 175.26 151.13 0)
			(effects
				(font
					(size 1.27 1.27)
				)
				(hide yes)
			)
		)
		(property "Author" "Antmicro"
			(at 190.5 153.67 0)
			(effects
				(font
					(size 1.27 1.27)
					(thickness 0.15)
				)
				(justify left bottom)
				(hide yes)
			)
		)
		(property "License" "Apache-2.0"
			(at 190.5 156.21 0)
			(effects
				(font
					(size 1.27 1.27)
					(thickness 0.15)
				)
				(justify left bottom)
				(hide yes)
			)
		)
		(pin "1"
		)
		(instances
			(project "jetson-orin-baseboard"
				(path ""
					(reference "#PWR027")
					(unit 1)
				)
			)
		)
	)
	(symbol
		(lib_name "TP_0.75mm_SMD_3")
		(lib_id "antmicroTestPoints:TP_0.75mm_SMD")
		(at 359.41 64.77 0)
		(unit 1)
		(exclude_from_sim no)
		(in_bom no)
		(on_board yes)
		(dnp no)
		(property "Reference" "TP12"
			(at 363.22 64.77 0)
			(effects
				(font
					(size 1.27 1.27)
				)
				(justify left)
			)
		)
		(property "Value" "TP_0.75mm_SMD"
			(at 369.57 68.58 0)
			(effects
				(font
					(size 1.27 1.27)
					(thickness 0.15)
				)
				(justify left bottom)
				(hide yes)
			)
		)
		(property "Footprint" "antmicro-footprints:TP_SMD_0.75mm"
			(at 369.57 71.12 0)
			(effects
				(font
					(size 1.27 1.27)
					(thickness 0.15)
				)
				(justify left bottom)
				(hide yes)
			)
		)
		(property "Datasheet" ""
			(at 377.19 77.47 0)
			(effects
				(font
					(size 1.27 1.27)
					(thickness 0.15)
				)
				(justify left bottom)
				(hide yes)
			)
		)
		(property "Description" ""
			(at 359.41 64.77 0)
			(effects
				(font
					(size 1.27 1.27)
				)
				(hide yes)
			)
		)
		(property "MPN" ""
			(at 370.205 76.2 0)
			(effects
				(font
					(size 1.27 1.27)
					(thickness 0.15)
				)
				(justify left bottom)
				(hide yes)
			)
		)
		(property "Manufacturer" ""
			(at 370.205 71.12 0)
			(effects
				(font
					(size 1.27 1.27)
					(thickness 0.15)
				)
				(justify left bottom)
				(hide yes)
			)
		)
		(property "Author" "Antmicro"
			(at 369.57 73.66 0)
			(effects
				(font
					(size 1.27 1.27)
					(thickness 0.15)
				)
				(justify left bottom)
				(hide yes)
			)
		)
		(property "License" "Apache-2.0"
			(at 369.57 76.2 0)
			(effects
				(font
					(size 1.27 1.27)
					(thickness 0.15)
				)
				(justify left bottom)
				(hide yes)
			)
		)
		(pin "1"
		)
		(instances
			(project "jetson-orin-baseboard"
				(path ""
					(reference "TP12")
					(unit 1)
				)
			)
		)
	)
	(symbol
		(lib_id "antmicroCapacitors0402:C_100n_0402")
		(at 130.81 92.71 90)
		(mirror x)
		(unit 1)
		(exclude_from_sim no)
		(in_bom yes)
		(on_board yes)
		(dnp no)
		(fields_autoplaced yes)
		(property "Reference" "C7"
			(at 133.35 93.9863 90)
			(effects
				(font
					(size 1.27 1.27)
				)
				(justify right)
			)
		)
		(property "Value" "C_100n_0402"
			(at 140.97 113.03 0)
			(effects
				(font
					(size 1.27 1.27)
					(thickness 0.15)
				)
				(justify left bottom)
				(hide yes)
			)
		)
		(property "Footprint" "antmicro-footprints:C_0402_1005Metric"
			(at 143.51 113.03 0)
			(effects
				(font
					(size 1.27 1.27)
					(thickness 0.15)
				)
				(justify left bottom)
				(hide yes)
			)
		)
		(property "Datasheet" "https://www.murata.com/products/productdetail?partno=GRM155R61H104KE14%23"
			(at 146.05 113.03 0)
			(effects
				(font
					(size 1.27 1.27)
					(thickness 0.15)
				)
				(justify left bottom)
				(hide yes)
			)
		)
		(property "Description" ""
			(at 130.81 92.71 0)
			(effects
				(font
					(size 1.27 1.27)
				)
				(hide yes)
			)
		)
		(property "Manufacturer" "Murata"
			(at 151.13 113.03 0)
			(effects
				(font
					(size 1.27 1.27)
					(thickness 0.15)
				)
				(justify left bottom)
				(hide yes)
			)
		)
		(property "MPN" "GRM155R61H104KE14D"
			(at 148.59 113.03 0)
			(effects
				(font
					(size 1.27 1.27)
					(thickness 0.15)
				)
				(justify left bottom)
				(hide yes)
			)
		)
		(property "Val" "100n"
			(at 133.35 96.5263 90)
			(effects
				(font
					(size 1.27 1.27)
					(thickness 0.15)
				)
				(justify right)
			)
		)
		(property "License" "Apache-2.0"
			(at 153.67 113.03 0)
			(effects
				(font
					(size 1.27 1.27)
					(thickness 0.15)
				)
				(justify left bottom)
				(hide yes)
			)
		)
		(property "Author" "Antmicro"
			(at 156.21 113.03 0)
			(effects
				(font
					(size 1.27 1.27)
					(thickness 0.15)
				)
				(justify left bottom)
				(hide yes)
			)
		)
		(property "Voltage" "50V"
			(at 158.75 113.03 0)
			(effects
				(font
					(size 1.27 1.27)
				)
				(justify left bottom)
				(hide yes)
			)
		)
		(property "Dielectric" "X5R"
			(at 161.29 113.03 0)
			(effects
				(font
					(size 1.27 1.27)
				)
				(justify left bottom)
				(hide yes)
			)
		)
		(pin "1"
		)
		(pin "2"
		)
		(instances
			(project "jetson-orin-baseboard"
				(path ""
					(reference "C7")
					(unit 1)
				)
			)
		)
	)
	(symbol
		(lib_name "GND_2")
		(lib_id "antmicropower:GND")
		(at 166.37 99.06 0)
		(unit 1)
		(exclude_from_sim no)
		(in_bom yes)
		(on_board yes)
		(dnp no)
		(property "Reference" "#PWR026"
			(at 166.37 105.41 0)
			(effects
				(font
					(size 1.27 1.27)
				)
				(justify left bottom)
				(hide yes)
			)
		)
		(property "Value" "GND"
			(at 166.37 102.87 0)
			(effects
				(font
					(size 1.27 1.27)
					(thickness 0.15)
				)
			)
		)
		(property "Footprint" ""
			(at 175.26 106.68 0)
			(effects
				(font
					(size 1.27 1.27)
					(thickness 0.15)
				)
				(justify left bottom)
				(hide yes)
			)
		)
		(property "Datasheet" ""
			(at 175.26 111.76 0)
			(effects
				(font
					(size 1.27 1.27)
					(thickness 0.15)
				)
				(justify left bottom)
				(hide yes)
			)
		)
		(property "Description" ""
			(at 166.37 99.06 0)
			(effects
				(font
					(size 1.27 1.27)
				)
				(hide yes)
			)
		)
		(property "Author" "Antmicro"
			(at 175.26 106.68 0)
			(effects
				(font
					(size 1.27 1.27)
					(thickness 0.15)
				)
				(justify left bottom)
				(hide yes)
			)
		)
		(property "License" "Apache-2.0"
			(at 175.26 109.22 0)
			(effects
				(font
					(size 1.27 1.27)
					(thickness 0.15)
				)
				(justify left bottom)
				(hide yes)
			)
		)
		(pin "1"
		)
		(instances
			(project "jetson-orin-baseboard"
				(path ""
					(reference "#PWR026")
					(unit 1)
				)
			)
		)
	)
	(symbol
		(lib_id "antmicropower:GND")
		(at 285.75 276.86 0)
		(unit 1)
		(exclude_from_sim no)
		(in_bom yes)
		(on_board yes)
		(dnp no)
		(property "Reference" "#PWR032"
			(at 285.75 283.21 0)
			(effects
				(font
					(size 1.27 1.27)
				)
				(justify left bottom)
				(hide yes)
			)
		)
		(property "Value" "GND"
			(at 283.845 280.67 0)
			(effects
				(font
					(size 1.27 1.27)
					(thickness 0.15)
				)
				(justify left)
			)
		)
		(property "Footprint" ""
			(at 294.64 284.48 0)
			(effects
				(font
					(size 1.27 1.27)
					(thickness 0.15)
				)
				(justify left bottom)
				(hide yes)
			)
		)
		(property "Datasheet" ""
			(at 294.64 289.56 0)
			(effects
				(font
					(size 1.27 1.27)
					(thickness 0.15)
				)
				(justify left bottom)
				(hide yes)
			)
		)
		(property "Description" ""
			(at 285.75 276.86 0)
			(effects
				(font
					(size 1.27 1.27)
				)
				(hide yes)
			)
		)
		(property "Author" "Antmicro"
			(at 294.64 284.48 0)
			(effects
				(font
					(size 1.27 1.27)
					(thickness 0.15)
				)
				(justify left bottom)
				(hide yes)
			)
		)
		(property "License" "Apache-2.0"
			(at 294.64 287.02 0)
			(effects
				(font
					(size 1.27 1.27)
					(thickness 0.15)
				)
				(justify left bottom)
				(hide yes)
			)
		)
		(pin "1"
		)
		(instances
			(project "jetson-orin-baseboard"
				(path ""
					(reference "#PWR032")
					(unit 1)
				)
			)
		)
	)
	(symbol
		(lib_name "+3V3_2")
		(lib_id "antmicropower:+3V3")
		(at 295.91 24.13 0)
		(unit 1)
		(exclude_from_sim no)
		(in_bom yes)
		(on_board yes)
		(dnp no)
		(property "Reference" "#PWR034"
			(at 295.91 27.94 0)
			(effects
				(font
					(size 1.27 1.27)
				)
				(justify left bottom)
				(hide yes)
			)
		)
		(property "Value" "+3V3"
			(at 292.735 20.32 0)
			(effects
				(font
					(size 1.27 1.27)
					(thickness 0.15)
				)
				(justify left)
			)
		)
		(property "Footprint" ""
			(at 311.15 31.75 0)
			(effects
				(font
					(size 1.27 1.27)
					(thickness 0.15)
				)
				(justify left bottom)
				(hide yes)
			)
		)
		(property "Datasheet" ""
			(at 311.15 34.29 0)
			(effects
				(font
					(size 1.27 1.27)
					(thickness 0.15)
				)
				(justify left bottom)
				(hide yes)
			)
		)
		(property "Description" ""
			(at 295.91 24.13 0)
			(effects
				(font
					(size 1.27 1.27)
				)
				(hide yes)
			)
		)
		(property "Author" "Antmicro"
			(at 311.15 26.67 0)
			(effects
				(font
					(size 1.27 1.27)
					(thickness 0.15)
				)
				(justify left bottom)
				(hide yes)
			)
		)
		(property "License" "Apache-2.0"
			(at 311.15 29.21 0)
			(effects
				(font
					(size 1.27 1.27)
					(thickness 0.15)
				)
				(justify left bottom)
				(hide yes)
			)
		)
		(pin "1"
		)
		(instances
			(project "jetson-orin-baseboard"
				(path ""
					(reference "#PWR034")
					(unit 1)
				)
			)
		)
	)
	(symbol
		(lib_id "antmicroCapacitors0402:C_100n_0402")
		(at 130.81 45.72 90)
		(mirror x)
		(unit 1)
		(exclude_from_sim no)
		(in_bom yes)
		(on_board yes)
		(dnp no)
		(fields_autoplaced yes)
		(property "Reference" "C8"
			(at 133.35 46.9963 90)
			(effects
				(font
					(size 1.27 1.27)
				)
				(justify right)
			)
		)
		(property "Value" "C_100n_0402"
			(at 140.97 66.04 0)
			(effects
				(font
					(size 1.27 1.27)
					(thickness 0.15)
				)
				(justify left bottom)
				(hide yes)
			)
		)
		(property "Footprint" "antmicro-footprints:C_0402_1005Metric"
			(at 143.51 66.04 0)
			(effects
				(font
					(size 1.27 1.27)
					(thickness 0.15)
				)
				(justify left bottom)
				(hide yes)
			)
		)
		(property "Datasheet" "https://www.murata.com/products/productdetail?partno=GRM155R61H104KE14%23"
			(at 146.05 66.04 0)
			(effects
				(font
					(size 1.27 1.27)
					(thickness 0.15)
				)
				(justify left bottom)
				(hide yes)
			)
		)
		(property "Description" ""
			(at 130.81 45.72 0)
			(effects
				(font
					(size 1.27 1.27)
				)
				(hide yes)
			)
		)
		(property "Manufacturer" "Murata"
			(at 151.13 66.04 0)
			(effects
				(font
					(size 1.27 1.27)
					(thickness 0.15)
				)
				(justify left bottom)
				(hide yes)
			)
		)
		(property "MPN" "GRM155R61H104KE14D"
			(at 148.59 66.04 0)
			(effects
				(font
					(size 1.27 1.27)
					(thickness 0.15)
				)
				(justify left bottom)
				(hide yes)
			)
		)
		(property "Val" "100n"
			(at 133.35 49.5363 90)
			(effects
				(font
					(size 1.27 1.27)
					(thickness 0.15)
				)
				(justify right)
			)
		)
		(property "License" "Apache-2.0"
			(at 153.67 66.04 0)
			(effects
				(font
					(size 1.27 1.27)
					(thickness 0.15)
				)
				(justify left bottom)
				(hide yes)
			)
		)
		(property "Author" "Antmicro"
			(at 156.21 66.04 0)
			(effects
				(font
					(size 1.27 1.27)
					(thickness 0.15)
				)
				(justify left bottom)
				(hide yes)
			)
		)
		(property "Voltage" "50V"
			(at 158.75 66.04 0)
			(effects
				(font
					(size 1.27 1.27)
				)
				(justify left bottom)
				(hide yes)
			)
		)
		(property "Dielectric" "X5R"
			(at 161.29 66.04 0)
			(effects
				(font
					(size 1.27 1.27)
				)
				(justify left bottom)
				(hide yes)
			)
		)
		(pin "1"
		)
		(pin "2"
		)
		(instances
			(project "jetson-orin-baseboard"
				(path ""
					(reference "C8")
					(unit 1)
				)
			)
		)
	)
	(symbol
		(lib_name "GND_6")
		(lib_id "antmicropower:GND")
		(at 379.73 35.56 0)
		(unit 1)
		(exclude_from_sim no)
		(in_bom yes)
		(on_board yes)
		(dnp no)
		(property "Reference" "#PWR042"
			(at 379.73 41.91 0)
			(effects
				(font
					(size 1.27 1.27)
				)
				(justify left bottom)
				(hide yes)
			)
		)
		(property "Value" "GND"
			(at 377.825 40.005 0)
			(effects
				(font
					(size 1.27 1.27)
					(thickness 0.15)
				)
				(justify left bottom)
			)
		)
		(property "Footprint" ""
			(at 388.62 43.18 0)
			(effects
				(font
					(size 1.27 1.27)
					(thickness 0.15)
				)
				(justify left bottom)
				(hide yes)
			)
		)
		(property "Datasheet" ""
			(at 388.62 48.26 0)
			(effects
				(font
					(size 1.27 1.27)
					(thickness 0.15)
				)
				(justify left bottom)
				(hide yes)
			)
		)
		(property "Description" ""
			(at 379.73 35.56 0)
			(effects
				(font
					(size 1.27 1.27)
				)
				(hide yes)
			)
		)
		(property "Author" "Antmicro"
			(at 388.62 43.18 0)
			(effects
				(font
					(size 1.27 1.27)
					(thickness 0.15)
				)
				(justify left bottom)
				(hide yes)
			)
		)
		(property "License" "Apache-2.0"
			(at 388.62 45.72 0)
			(effects
				(font
					(size 1.27 1.27)
					(thickness 0.15)
				)
				(justify left bottom)
				(hide yes)
			)
		)
		(pin "1"
		)
		(instances
			(project "jetson-orin-baseboard"
				(path ""
					(reference "#PWR042")
					(unit 1)
				)
			)
		)
	)
	(symbol
		(lib_id "antmicroResistors0402:R_47k_0402")
		(at 250.19 200.66 0)
		(unit 1)
		(exclude_from_sim no)
		(in_bom no)
		(on_board yes)
		(dnp yes)
		(property "Reference" "R32"
			(at 255.27 200.025 0)
			(effects
				(font
					(size 1.27 1.27)
				)
				(justify left bottom)
			)
		)
		(property "Value" "R_47k_0402"
			(at 270.51 213.36 0)
			(effects
				(font
					(size 1.27 1.27)
					(thickness 0.15)
				)
				(justify left bottom)
				(hide yes)
			)
		)
		(property "Footprint" "antmicro-footprints:R_0402_1005Metric"
			(at 270.51 215.9 0)
			(effects
				(font
					(size 1.27 1.27)
					(thickness 0.15)
				)
				(justify left bottom)
				(hide yes)
			)
		)
		(property "Datasheet" "https://www.bourns.com/docs/product-datasheets/cr.pdf"
			(at 270.51 218.44 0)
			(effects
				(font
					(size 1.27 1.27)
					(thickness 0.15)
				)
				(justify left bottom)
				(hide yes)
			)
		)
		(property "Description" ""
			(at 250.19 200.66 0)
			(effects
				(font
					(size 1.27 1.27)
				)
				(hide yes)
			)
		)
		(property "Manufacturer" "Bourns"
			(at 270.51 223.52 0)
			(effects
				(font
					(size 1.27 1.27)
					(thickness 0.15)
				)
				(justify left bottom)
				(hide yes)
			)
		)
		(property "MPN" "CR0402-FX-4702GLF"
			(at 270.51 220.98 0)
			(effects
				(font
					(size 1.27 1.27)
					(thickness 0.15)
				)
				(justify left bottom)
				(hide yes)
			)
		)
		(property "Val" "47k"
			(at 246.38 200.025 0)
			(effects
				(font
					(size 1.27 1.27)
					(thickness 0.15)
				)
				(justify left bottom)
			)
		)
		(property "License" "Apache-2.0"
			(at 270.51 226.06 0)
			(effects
				(font
					(size 1.27 1.27)
					(thickness 0.15)
				)
				(justify left bottom)
				(hide yes)
			)
		)
		(property "Author" "Antmicro"
			(at 270.51 228.6 0)
			(effects
				(font
					(size 1.27 1.27)
					(thickness 0.15)
				)
				(justify left bottom)
				(hide yes)
			)
		)
		(property "Tolerance" "1%"
			(at 270.51 210.82 0)
			(effects
				(font
					(size 1.27 1.27)
				)
				(justify left bottom)
				(hide yes)
			)
		)
		(pin "1"
		)
		(pin "2"
		)
		(instances
			(project "jetson-orin-baseboard"
				(path ""
					(reference "R32")
					(unit 1)
				)
			)
		)
	)
	(symbol
		(lib_name "GND_7")
		(lib_id "antmicropower:GND")
		(at 349.25 35.56 0)
		(unit 1)
		(exclude_from_sim no)
		(in_bom yes)
		(on_board yes)
		(dnp no)
		(property "Reference" "#PWR037"
			(at 349.25 41.91 0)
			(effects
				(font
					(size 1.27 1.27)
				)
				(justify left bottom)
				(hide yes)
			)
		)
		(property "Value" "GND"
			(at 347.345 40.005 0)
			(effects
				(font
					(size 1.27 1.27)
					(thickness 0.15)
				)
				(justify left bottom)
			)
		)
		(property "Footprint" ""
			(at 358.14 43.18 0)
			(effects
				(font
					(size 1.27 1.27)
					(thickness 0.15)
				)
				(justify left bottom)
				(hide yes)
			)
		)
		(property "Datasheet" ""
			(at 358.14 48.26 0)
			(effects
				(font
					(size 1.27 1.27)
					(thickness 0.15)
				)
				(justify left bottom)
				(hide yes)
			)
		)
		(property "Description" ""
			(at 349.25 35.56 0)
			(effects
				(font
					(size 1.27 1.27)
				)
				(hide yes)
			)
		)
		(property "Author" "Antmicro"
			(at 358.14 43.18 0)
			(effects
				(font
					(size 1.27 1.27)
					(thickness 0.15)
				)
				(justify left bottom)
				(hide yes)
			)
		)
		(property "License" "Apache-2.0"
			(at 358.14 45.72 0)
			(effects
				(font
					(size 1.27 1.27)
					(thickness 0.15)
				)
				(justify left bottom)
				(hide yes)
			)
		)
		(pin "1"
		)
		(instances
			(project "jetson-orin-baseboard"
				(path ""
					(reference "#PWR037")
					(unit 1)
				)
			)
		)
	)
	(symbol
		(lib_id "antmicropower:+3V3")
		(at 259.08 149.86 0)
		(unit 1)
		(exclude_from_sim no)
		(in_bom yes)
		(on_board yes)
		(dnp no)
		(property "Reference" "#PWR031"
			(at 259.08 153.67 0)
			(effects
				(font
					(size 1.27 1.27)
				)
				(justify left bottom)
				(hide yes)
			)
		)
		(property "Value" "+3V3"
			(at 255.905 146.685 0)
			(effects
				(font
					(size 1.27 1.27)
					(thickness 0.15)
				)
				(justify left bottom)
			)
		)
		(property "Footprint" ""
			(at 274.32 157.48 0)
			(effects
				(font
					(size 1.27 1.27)
					(thickness 0.15)
				)
				(justify left bottom)
				(hide yes)
			)
		)
		(property "Datasheet" ""
			(at 274.32 160.02 0)
			(effects
				(font
					(size 1.27 1.27)
					(thickness 0.15)
				)
				(justify left bottom)
				(hide yes)
			)
		)
		(property "Description" ""
			(at 259.08 149.86 0)
			(effects
				(font
					(size 1.27 1.27)
				)
				(hide yes)
			)
		)
		(property "Author" "Antmicro"
			(at 274.32 152.4 0)
			(effects
				(font
					(size 1.27 1.27)
					(thickness 0.15)
				)
				(justify left bottom)
				(hide yes)
			)
		)
		(property "License" "Apache-2.0"
			(at 274.32 154.94 0)
			(effects
				(font
					(size 1.27 1.27)
					(thickness 0.15)
				)
				(justify left bottom)
				(hide yes)
			)
		)
		(pin "1"
		)
		(instances
			(project "jetson-orin-baseboard"
				(path ""
					(reference "#PWR031")
					(unit 1)
				)
			)
		)
	)
	(symbol
		(lib_id "antmicroModules:Mech_M2_2280_H2.5mm")
		(at 395.605 110.49 180)
		(unit 1)
		(exclude_from_sim no)
		(in_bom no)
		(on_board yes)
		(dnp yes)
		(property "Reference" "M3"
			(at 390.525 99.695 0)
			(effects
				(font
					(size 1.27 1.27)
				)
			)
		)
		(property "Value" "Mech_M2_2280_H2.5mm"
			(at 390.525 102.235 0)
			(effects
				(font
					(size 1.27 1.27)
					(thickness 0.15)
				)
			)
		)
		(property "Footprint" "antmicro-footprints:Mech_M2_2280_H2.5mm"
			(at 370.205 105.41 0)
			(effects
				(font
					(size 1.27 1.27)
					(thickness 0.15)
				)
				(justify left bottom)
				(hide yes)
			)
		)
		(property "Datasheet" ""
			(at 370.205 102.87 0)
			(effects
				(font
					(size 1.27 1.27)
					(thickness 0.15)
				)
				(justify left bottom)
				(hide yes)
			)
		)
		(property "Description" ""
			(at 395.605 110.49 0)
			(effects
				(font
					(size 1.27 1.27)
				)
				(hide yes)
			)
		)
		(property "Manufacturer" ""
			(at 395.605 110.49 0)
			(effects
				(font
					(size 1.27 1.27)
				)
				(hide yes)
			)
		)
		(property "MPN" ""
			(at 395.605 110.49 0)
			(effects
				(font
					(size 1.27 1.27)
				)
			)
		)
		(property "Author" "Antmicro"
			(at 370.205 100.33 0)
			(effects
				(font
					(size 1.27 1.27)
					(thickness 0.15)
				)
				(justify left bottom)
				(hide yes)
			)
		)
		(property "License" "Apache-2.0"
			(at 370.205 97.79 0)
			(effects
				(font
					(size 1.27 1.27)
					(thickness 0.15)
				)
				(justify left bottom)
				(hide yes)
			)
		)
		(instances
			(project "jetson-orin-baseboard"
				(path ""
					(reference "M3")
					(unit 1)
				)
			)
		)
	)
	(symbol
		(lib_id "antmicroCapacitors0402:C_220n_0402")
		(at 161.29 180.34 0)
		(unit 1)
		(exclude_from_sim no)
		(in_bom yes)
		(on_board yes)
		(dnp no)
		(property "Reference" "C10"
			(at 165.1 179.705 0)
			(effects
				(font
					(size 1.27 1.27)
				)
				(justify left bottom)
			)
		)
		(property "Value" "C_220n_0402"
			(at 181.61 190.5 0)
			(effects
				(font
					(size 1.27 1.27)
					(thickness 0.15)
				)
				(justify left bottom)
				(hide yes)
			)
		)
		(property "Footprint" "antmicro-footprints:C_0402_1005Metric"
			(at 181.61 193.04 0)
			(effects
				(font
					(size 1.27 1.27)
					(thickness 0.15)
				)
				(justify left bottom)
				(hide yes)
			)
		)
		(property "Datasheet" "https://www.yageo.com/en/Chart/Download/pdf/CC0402KRX5R6BB224"
			(at 181.61 195.58 0)
			(effects
				(font
					(size 1.27 1.27)
					(thickness 0.15)
				)
				(justify left bottom)
				(hide yes)
			)
		)
		(property "Description" ""
			(at 161.29 180.34 0)
			(effects
				(font
					(size 1.27 1.27)
				)
				(hide yes)
			)
		)
		(property "Manufacturer" "YAGEO"
			(at 181.61 200.66 0)
			(effects
				(font
					(size 1.27 1.27)
					(thickness 0.15)
				)
				(justify left bottom)
				(hide yes)
			)
		)
		(property "MPN" "CC0402KRX5R6BB224"
			(at 181.61 198.12 0)
			(effects
				(font
					(size 1.27 1.27)
					(thickness 0.15)
				)
				(justify left bottom)
				(hide yes)
			)
		)
		(property "Val" "220n"
			(at 157.48 182.245 0)
			(effects
				(font
					(size 1.27 1.27)
					(thickness 0.15)
				)
				(justify left bottom)
			)
		)
		(property "License" "Apache-2.0"
			(at 181.61 203.2 0)
			(effects
				(font
					(size 1.27 1.27)
					(thickness 0.15)
				)
				(justify left bottom)
				(hide yes)
			)
		)
		(property "Author" "Antmicro"
			(at 181.61 205.74 0)
			(effects
				(font
					(size 1.27 1.27)
					(thickness 0.15)
				)
				(justify left bottom)
				(hide yes)
			)
		)
		(property "Voltage" ""
			(at 181.61 208.28 0)
			(effects
				(font
					(size 1.27 1.27)
				)
				(justify left bottom)
				(hide yes)
			)
		)
		(property "Dielectric" ""
			(at 181.61 210.82 0)
			(effects
				(font
					(size 1.27 1.27)
				)
				(justify left bottom)
				(hide yes)
			)
		)
		(pin "1"
		)
		(pin "2"
		)
		(instances
			(project "jetson-orin-baseboard"
				(path ""
					(reference "C10")
					(unit 1)
				)
			)
		)
	)
	(symbol
		(lib_name "C_220n_0402_7")
		(lib_id "antmicroCapacitors0402:C_220n_0402")
		(at 281.94 100.33 180)
		(unit 1)
		(exclude_from_sim no)
		(in_bom yes)
		(on_board yes)
		(dnp no)
		(property "Reference" "C16"
			(at 284.48 98.425 0)
			(effects
				(font
					(size 1.27 1.27)
				)
				(justify left bottom)
			)
		)
		(property "Value" "C_220n_0402"
			(at 261.62 90.17 0)
			(effects
				(font
					(size 1.27 1.27)
					(thickness 0.15)
				)
				(justify left bottom)
				(hide yes)
			)
		)
		(property "Footprint" "antmicro-footprints:C_0402_1005Metric"
			(at 261.62 87.63 0)
			(effects
				(font
					(size 1.27 1.27)
					(thickness 0.15)
				)
				(justify left bottom)
				(hide yes)
			)
		)
		(property "Datasheet" "https://www.yageo.com/en/Chart/Download/pdf/CC0402KRX5R6BB224"
			(at 261.62 85.09 0)
			(effects
				(font
					(size 1.27 1.27)
					(thickness 0.15)
				)
				(justify left bottom)
				(hide yes)
			)
		)
		(property "Description" ""
			(at 281.94 100.33 0)
			(effects
				(font
					(size 1.27 1.27)
				)
				(hide yes)
			)
		)
		(property "Manufacturer" "YAGEO"
			(at 261.62 80.01 0)
			(effects
				(font
					(size 1.27 1.27)
					(thickness 0.15)
				)
				(justify left bottom)
				(hide yes)
			)
		)
		(property "MPN" "CC0402KRX5R6BB224"
			(at 261.62 82.55 0)
			(effects
				(font
					(size 1.27 1.27)
					(thickness 0.15)
				)
				(justify left bottom)
				(hide yes)
			)
		)
		(property "Val" "220n"
			(at 278.13 100.965 0)
			(effects
				(font
					(size 1.27 1.27)
					(thickness 0.15)
				)
				(justify left bottom)
			)
		)
		(property "License" "Apache-2.0"
			(at 261.62 77.47 0)
			(effects
				(font
					(size 1.27 1.27)
					(thickness 0.15)
				)
				(justify left bottom)
				(hide yes)
			)
		)
		(property "Author" "Antmicro"
			(at 261.62 74.93 0)
			(effects
				(font
					(size 1.27 1.27)
					(thickness 0.15)
				)
				(justify left bottom)
				(hide yes)
			)
		)
		(property "Voltage" ""
			(at 261.62 72.39 0)
			(effects
				(font
					(size 1.27 1.27)
				)
				(justify left bottom)
				(hide yes)
			)
		)
		(property "Dielectric" ""
			(at 261.62 69.85 0)
			(effects
				(font
					(size 1.27 1.27)
				)
				(justify left bottom)
				(hide yes)
			)
		)
		(pin "1"
		)
		(pin "2"
		)
		(instances
			(project "jetson-orin-baseboard"
				(path ""
					(reference "C16")
					(unit 1)
				)
			)
		)
	)
	(symbol
		(lib_id "antmicroLogicBuffersDriversReceiversTransceivers:74LVC2G07_SOT457")
		(at 152.4 48.26 0)
		(unit 1)
		(exclude_from_sim no)
		(in_bom no)
		(on_board yes)
		(dnp yes)
		(property "Reference" "U2"
			(at 158.75 40.64 0)
			(effects
				(font
					(size 1.27 1.27)
				)
			)
		)
		(property "Value" "74LVC2G07_SOT457"
			(at 181.61 54.61 0)
			(effects
				(font
					(size 1.27 1.27)
					(thickness 0.15)
				)
				(justify left bottom)
				(hide yes)
			)
		)
		(property "Footprint" "antmicro-footprints:SC-74-6_1.5x2.9mm_P0.95mm"
			(at 181.61 57.15 0)
			(effects
				(font
					(size 1.27 1.27)
					(thickness 0.15)
				)
				(justify left bottom)
				(hide yes)
			)
		)
		(property "Datasheet" "https://www.tme.eu/Document/2ad9356043a4952b9021ef50162f8c34/74LVC2G07.pdf"
			(at 181.61 59.69 0)
			(effects
				(font
					(size 1.27 1.27)
					(thickness 0.15)
				)
				(justify left bottom)
				(hide yes)
			)
		)
		(property "Description" ""
			(at 152.4 48.26 0)
			(effects
				(font
					(size 1.27 1.27)
				)
				(hide yes)
			)
		)
		(property "Manufacturer" "Nexperia"
			(at 181.61 62.23 0)
			(effects
				(font
					(size 1.27 1.27)
					(thickness 0.15)
				)
				(justify left bottom)
				(hide yes)
			)
		)
		(property "MPN" "74LVC2G07GV,125"
			(at 158.75 43.18 0)
			(effects
				(font
					(size 1.27 1.27)
					(thickness 0.15)
				)
			)
		)
		(property "Author" "Antmicro"
			(at 181.61 67.31 0)
			(effects
				(font
					(size 1.27 1.27)
					(thickness 0.15)
				)
				(justify left bottom)
				(hide yes)
			)
		)
		(property "License" "Apache-2.0"
			(at 181.61 69.85 0)
			(effects
				(font
					(size 1.27 1.27)
					(thickness 0.15)
				)
				(justify left bottom)
				(hide yes)
			)
		)
		(pin "1"
		)
		(pin "2"
		)
		(pin "3"
		)
		(pin "4"
		)
		(pin "5"
		)
		(pin "6"
		)
		(instances
			(project "jetson-orin-baseboard"
				(path ""
					(reference "U2")
					(unit 1)
				)
			)
		)
	)
	(symbol
		(lib_name "+3V3_1")
		(lib_id "antmicropower:+3V3")
		(at 130.81 91.44 0)
		(unit 1)
		(exclude_from_sim no)
		(in_bom yes)
		(on_board yes)
		(dnp no)
		(property "Reference" "#PWR021"
			(at 130.81 95.25 0)
			(effects
				(font
					(size 1.27 1.27)
				)
				(justify left bottom)
				(hide yes)
			)
		)
		(property "Value" "+3V3"
			(at 130.175 87.63 0)
			(effects
				(font
					(size 1.27 1.27)
					(thickness 0.15)
				)
			)
		)
		(property "Footprint" ""
			(at 146.05 99.06 0)
			(effects
				(font
					(size 1.27 1.27)
					(thickness 0.15)
				)
				(justify left bottom)
				(hide yes)
			)
		)
		(property "Datasheet" ""
			(at 146.05 101.6 0)
			(effects
				(font
					(size 1.27 1.27)
					(thickness 0.15)
				)
				(justify left bottom)
				(hide yes)
			)
		)
		(property "Description" ""
			(at 130.81 91.44 0)
			(effects
				(font
					(size 1.27 1.27)
				)
				(hide yes)
			)
		)
		(property "Author" "Antmicro"
			(at 146.05 93.98 0)
			(effects
				(font
					(size 1.27 1.27)
					(thickness 0.15)
				)
				(justify left bottom)
				(hide yes)
			)
		)
		(property "License" "Apache-2.0"
			(at 146.05 96.52 0)
			(effects
				(font
					(size 1.27 1.27)
					(thickness 0.15)
				)
				(justify left bottom)
				(hide yes)
			)
		)
		(pin "1"
		)
		(instances
			(project "jetson-orin-baseboard"
				(path ""
					(reference "#PWR021")
					(unit 1)
				)
			)
		)
	)
	(symbol
		(lib_id "antmicroResistors0402:R_200R_0402")
		(at 254 232.41 90)
		(unit 1)
		(exclude_from_sim no)
		(in_bom yes)
		(on_board yes)
		(dnp no)
		(property "Reference" "R187"
			(at 255.27 228.6 90)
			(effects
				(font
					(size 1.27 1.27)
				)
				(justify right)
			)
		)
		(property "Value" "R_200R_0402"
			(at 266.7 212.09 0)
			(effects
				(font
					(size 1.27 1.27)
					(thickness 0.15)
				)
				(justify left bottom)
				(hide yes)
			)
		)
		(property "Footprint" "antmicro-footprints:R_0402_1005Metric"
			(at 269.24 212.09 0)
			(effects
				(font
					(size 1.27 1.27)
					(thickness 0.15)
				)
				(justify left bottom)
				(hide yes)
			)
		)
		(property "Datasheet" "https://www.bourns.com/docs/product-datasheets/cr.pdf"
			(at 271.78 212.09 0)
			(effects
				(font
					(size 1.27 1.27)
					(thickness 0.15)
				)
				(justify left bottom)
				(hide yes)
			)
		)
		(property "Description" ""
			(at 254 232.41 0)
			(effects
				(font
					(size 1.27 1.27)
				)
				(hide yes)
			)
		)
		(property "Manufacturer" "Bourns"
			(at 276.86 212.09 0)
			(effects
				(font
					(size 1.27 1.27)
					(thickness 0.15)
				)
				(justify left bottom)
				(hide yes)
			)
		)
		(property "MPN" "CR0402-FX-2000GLF"
			(at 274.32 212.09 0)
			(effects
				(font
					(size 1.27 1.27)
					(thickness 0.15)
				)
				(justify left bottom)
				(hide yes)
			)
		)
		(property "Val" "200R"
			(at 255.27 231.14 90)
			(effects
				(font
					(size 1.27 1.27)
					(thickness 0.15)
				)
				(justify right)
			)
		)
		(property "License" "Apache-2.0"
			(at 279.4 212.09 0)
			(effects
				(font
					(size 1.27 1.27)
					(thickness 0.15)
				)
				(justify left bottom)
				(hide yes)
			)
		)
		(property "Author" "Antmicro"
			(at 281.94 212.09 0)
			(effects
				(font
					(size 1.27 1.27)
					(thickness 0.15)
				)
				(justify left bottom)
				(hide yes)
			)
		)
		(property "Tolerance" "1%"
			(at 264.16 212.09 0)
			(effects
				(font
					(size 1.27 1.27)
				)
				(justify left bottom)
				(hide yes)
			)
		)
		(pin "1"
		)
		(pin "2"
		)
		(instances
			(project "jetson-orin-baseboard"
				(path ""
					(reference "R187")
					(unit 1)
				)
			)
		)
	)
	(symbol
		(lib_name "R_0R_0402_3")
		(lib_id "antmicroResistors0402:R_0R_0402")
		(at 64.77 34.29 0)
		(unit 1)
		(exclude_from_sim no)
		(in_bom yes)
		(on_board yes)
		(dnp no)
		(property "Reference" "R16"
			(at 69.85 33.655 0)
			(effects
				(font
					(size 1.27 1.27)
				)
				(justify left bottom)
			)
		)
		(property "Value" "R_0R_0402"
			(at 85.09 46.99 0)
			(effects
				(font
					(size 1.27 1.27)
					(thickness 0.15)
				)
				(justify left bottom)
				(hide yes)
			)
		)
		(property "Footprint" "antmicro-footprints:R_0402_1005Metric"
			(at 85.09 49.53 0)
			(effects
				(font
					(size 1.27 1.27)
					(thickness 0.15)
				)
				(justify left bottom)
				(hide yes)
			)
		)
		(property "Datasheet" "https://industrial.panasonic.com/cdbs/www-data/pdf/RDA0000/AOA0000C301.pdf"
			(at 85.09 52.07 0)
			(effects
				(font
					(size 1.27 1.27)
					(thickness 0.15)
				)
				(justify left bottom)
				(hide yes)
			)
		)
		(property "Description" ""
			(at 64.77 34.29 0)
			(effects
				(font
					(size 1.27 1.27)
				)
				(hide yes)
			)
		)
		(property "Manufacturer" "Panasonic"
			(at 85.09 57.15 0)
			(effects
				(font
					(size 1.27 1.27)
					(thickness 0.15)
				)
				(justify left bottom)
				(hide yes)
			)
		)
		(property "MPN" "ERJ2GE0R00X"
			(at 85.09 54.61 0)
			(effects
				(font
					(size 1.27 1.27)
					(thickness 0.15)
				)
				(justify left bottom)
				(hide yes)
			)
		)
		(property "Val" "0R"
			(at 62.23 33.655 0)
			(effects
				(font
					(size 1.27 1.27)
					(thickness 0.15)
				)
				(justify left bottom)
			)
		)
		(property "License" "Apache-2.0"
			(at 85.09 59.69 0)
			(effects
				(font
					(size 1.27 1.27)
					(thickness 0.15)
				)
				(justify left bottom)
				(hide yes)
			)
		)
		(property "Author" "Antmicro"
			(at 85.09 62.23 0)
			(effects
				(font
					(size 1.27 1.27)
					(thickness 0.15)
				)
				(justify left bottom)
				(hide yes)
			)
		)
		(property "Tolerance" "~"
			(at 85.09 44.45 0)
			(effects
				(font
					(size 1.27 1.27)
				)
				(justify left bottom)
				(hide yes)
			)
		)
		(property "Current" "1A"
			(at 85.09 64.77 0)
			(effects
				(font
					(size 1.27 1.27)
					(thickness 0.15)
				)
				(justify left bottom)
				(hide yes)
			)
		)
		(pin "1"
		)
		(pin "2"
		)
		(instances
			(project "jetson-orin-baseboard"
				(path ""
					(reference "R16")
					(unit 1)
				)
			)
		)
	)
	(symbol
		(lib_name "C_220n_0402_8")
		(lib_id "antmicroCapacitors0402:C_220n_0402")
		(at 281.94 54.61 180)
		(unit 1)
		(exclude_from_sim no)
		(in_bom yes)
		(on_board yes)
		(dnp no)
		(property "Reference" "C13"
			(at 284.48 52.705 0)
			(effects
				(font
					(size 1.27 1.27)
				)
				(justify left bottom)
			)
		)
		(property "Value" "C_220n_0402"
			(at 261.62 44.45 0)
			(effects
				(font
					(size 1.27 1.27)
					(thickness 0.15)
				)
				(justify left bottom)
				(hide yes)
			)
		)
		(property "Footprint" "antmicro-footprints:C_0402_1005Metric"
			(at 261.62 41.91 0)
			(effects
				(font
					(size 1.27 1.27)
					(thickness 0.15)
				)
				(justify left bottom)
				(hide yes)
			)
		)
		(property "Datasheet" "https://www.yageo.com/en/Chart/Download/pdf/CC0402KRX5R6BB224"
			(at 261.62 39.37 0)
			(effects
				(font
					(size 1.27 1.27)
					(thickness 0.15)
				)
				(justify left bottom)
				(hide yes)
			)
		)
		(property "Description" ""
			(at 281.94 54.61 0)
			(effects
				(font
					(size 1.27 1.27)
				)
				(hide yes)
			)
		)
		(property "Manufacturer" "YAGEO"
			(at 261.62 34.29 0)
			(effects
				(font
					(size 1.27 1.27)
					(thickness 0.15)
				)
				(justify left bottom)
				(hide yes)
			)
		)
		(property "MPN" "CC0402KRX5R6BB224"
			(at 261.62 36.83 0)
			(effects
				(font
					(size 1.27 1.27)
					(thickness 0.15)
				)
				(justify left bottom)
				(hide yes)
			)
		)
		(property "Val" "220n"
			(at 278.13 55.245 0)
			(effects
				(font
					(size 1.27 1.27)
					(thickness 0.15)
				)
				(justify left bottom)
			)
		)
		(property "License" "Apache-2.0"
			(at 261.62 31.75 0)
			(effects
				(font
					(size 1.27 1.27)
					(thickness 0.15)
				)
				(justify left bottom)
				(hide yes)
			)
		)
		(property "Author" "Antmicro"
			(at 261.62 29.21 0)
			(effects
				(font
					(size 1.27 1.27)
					(thickness 0.15)
				)
				(justify left bottom)
				(hide yes)
			)
		)
		(property "Voltage" ""
			(at 261.62 26.67 0)
			(effects
				(font
					(size 1.27 1.27)
				)
				(justify left bottom)
				(hide yes)
			)
		)
		(property "Dielectric" ""
			(at 261.62 24.13 0)
			(effects
				(font
					(size 1.27 1.27)
				)
				(justify left bottom)
				(hide yes)
			)
		)
		(pin "1"
		)
		(pin "2"
		)
		(instances
			(project "jetson-orin-baseboard"
				(path ""
					(reference "C13")
					(unit 1)
				)
			)
		)
	)
	(symbol
		(lib_name "Spacer_Drill3.7mm_H2.5mm_9774025151R_1")
		(lib_id "antmicroMechanicalParts:Spacer_Drill3.7mm_H2.5mm_9774025151R")
		(at 396.24 121.92 180)
		(unit 1)
		(exclude_from_sim no)
		(in_bom yes)
		(on_board yes)
		(dnp no)
		(fields_autoplaced yes)
		(property "Reference" "SP8"
			(at 386.715 120.65 0)
			(effects
				(font
					(size 1.27 1.27)
					(thickness 0.15)
				)
				(justify left)
			)
		)
		(property "Value" "Spacer_Drill3.7mm_H2.5mm_9774025151R"
			(at 386.715 123.19 0)
			(effects
				(font
					(size 1.27 1.27)
					(thickness 0.15)
				)
				(justify left)
			)
		)
		(property "Footprint" "antmicro-footprints:Spacer_Drill3.7mm_H2.5mm_9774025151R"
			(at 373.38 114.3 0)
			(effects
				(font
					(size 1.27 1.27)
					(thickness 0.15)
				)
				(justify left bottom)
				(hide yes)
			)
		)
		(property "Datasheet" "https://www.we-online.com/components/products/datasheet/9774025151R.pdf"
			(at 373.38 111.76 0)
			(effects
				(font
					(size 1.27 1.27)
					(thickness 0.15)
				)
				(justify left bottom)
				(hide yes)
			)
		)
		(property "Description" ""
			(at 396.24 121.92 0)
			(effects
				(font
					(size 1.27 1.27)
				)
				(hide yes)
			)
		)
		(property "Manufacturer" "Würth Elektronik"
			(at 373.38 109.22 0)
			(effects
				(font
					(size 1.27 1.27)
					(thickness 0.15)
				)
				(justify left bottom)
				(hide yes)
			)
		)
		(property "MPN" "9774025151R"
			(at 373.38 106.68 0)
			(effects
				(font
					(size 1.27 1.27)
					(thickness 0.15)
				)
				(justify left bottom)
				(hide yes)
			)
		)
		(property "Author" "Antmicro"
			(at 373.38 104.14 0)
			(effects
				(font
					(size 1.27 1.27)
					(thickness 0.15)
				)
				(justify left bottom)
				(hide yes)
			)
		)
		(property "License" "Apache-2.0"
			(at 373.38 101.6 0)
			(effects
				(font
					(size 1.27 1.27)
					(thickness 0.15)
				)
				(justify left bottom)
				(hide yes)
			)
		)
		(pin "1"
		)
		(instances
			(project "jetson-orin-baseboard"
				(path ""
					(reference "SP8")
					(unit 1)
				)
			)
		)
	)
	(symbol
		(lib_id "antmicroTestPoints:TP_0.75mm_SMD")
		(at 264.16 185.42 0)
		(unit 1)
		(exclude_from_sim no)
		(in_bom no)
		(on_board yes)
		(dnp no)
		(property "Reference" "TP6"
			(at 267.97 186.055 0)
			(effects
				(font
					(size 1.27 1.27)
				)
				(justify left bottom)
			)
		)
		(property "Value" "TP_0.75mm_SMD"
			(at 274.32 189.23 0)
			(effects
				(font
					(size 1.27 1.27)
					(thickness 0.15)
				)
				(justify left bottom)
				(hide yes)
			)
		)
		(property "Footprint" "antmicro-footprints:TP_SMD_0.75mm"
			(at 274.32 191.77 0)
			(effects
				(font
					(size 1.27 1.27)
					(thickness 0.15)
				)
				(justify left bottom)
				(hide yes)
			)
		)
		(property "Datasheet" ""
			(at 281.94 198.12 0)
			(effects
				(font
					(size 1.27 1.27)
					(thickness 0.15)
				)
				(justify left bottom)
				(hide yes)
			)
		)
		(property "Description" ""
			(at 264.16 185.42 0)
			(effects
				(font
					(size 1.27 1.27)
				)
				(hide yes)
			)
		)
		(property "MPN" ""
			(at 274.955 196.85 0)
			(effects
				(font
					(size 1.27 1.27)
					(thickness 0.15)
				)
				(justify left bottom)
				(hide yes)
			)
		)
		(property "Manufacturer" ""
			(at 274.955 191.77 0)
			(effects
				(font
					(size 1.27 1.27)
					(thickness 0.15)
				)
				(justify left bottom)
				(hide yes)
			)
		)
		(property "Author" "Antmicro"
			(at 274.32 194.31 0)
			(effects
				(font
					(size 1.27 1.27)
					(thickness 0.15)
				)
				(justify left bottom)
				(hide yes)
			)
		)
		(property "License" "Apache-2.0"
			(at 274.32 196.85 0)
			(effects
				(font
					(size 1.27 1.27)
					(thickness 0.15)
				)
				(justify left bottom)
				(hide yes)
			)
		)
		(pin "1"
		)
		(instances
			(project "jetson-orin-baseboard"
				(path ""
					(reference "TP6")
					(unit 1)
				)
			)
		)
	)
	(symbol
		(lib_name "R_0R_0402_4")
		(lib_id "antmicroResistors0402:R_0R_0402")
		(at 64.77 36.83 0)
		(unit 1)
		(exclude_from_sim no)
		(in_bom yes)
		(on_board yes)
		(dnp no)
		(property "Reference" "R17"
			(at 69.85 36.195 0)
			(effects
				(font
					(size 1.27 1.27)
				)
				(justify left bottom)
			)
		)
		(property "Value" "R_0R_0402"
			(at 85.09 49.53 0)
			(effects
				(font
					(size 1.27 1.27)
					(thickness 0.15)
				)
				(justify left bottom)
				(hide yes)
			)
		)
		(property "Footprint" "antmicro-footprints:R_0402_1005Metric"
			(at 85.09 52.07 0)
			(effects
				(font
					(size 1.27 1.27)
					(thickness 0.15)
				)
				(justify left bottom)
				(hide yes)
			)
		)
		(property "Datasheet" "https://industrial.panasonic.com/cdbs/www-data/pdf/RDA0000/AOA0000C301.pdf"
			(at 85.09 54.61 0)
			(effects
				(font
					(size 1.27 1.27)
					(thickness 0.15)
				)
				(justify left bottom)
				(hide yes)
			)
		)
		(property "Description" ""
			(at 64.77 36.83 0)
			(effects
				(font
					(size 1.27 1.27)
				)
				(hide yes)
			)
		)
		(property "Manufacturer" "Panasonic"
			(at 85.09 59.69 0)
			(effects
				(font
					(size 1.27 1.27)
					(thickness 0.15)
				)
				(justify left bottom)
				(hide yes)
			)
		)
		(property "MPN" "ERJ2GE0R00X"
			(at 85.09 57.15 0)
			(effects
				(font
					(size 1.27 1.27)
					(thickness 0.15)
				)
				(justify left bottom)
				(hide yes)
			)
		)
		(property "Val" "0R"
			(at 62.23 36.195 0)
			(effects
				(font
					(size 1.27 1.27)
					(thickness 0.15)
				)
				(justify left bottom)
			)
		)
		(property "License" "Apache-2.0"
			(at 85.09 62.23 0)
			(effects
				(font
					(size 1.27 1.27)
					(thickness 0.15)
				)
				(justify left bottom)
				(hide yes)
			)
		)
		(property "Author" "Antmicro"
			(at 85.09 64.77 0)
			(effects
				(font
					(size 1.27 1.27)
					(thickness 0.15)
				)
				(justify left bottom)
				(hide yes)
			)
		)
		(property "Tolerance" "~"
			(at 85.09 46.99 0)
			(effects
				(font
					(size 1.27 1.27)
				)
				(justify left bottom)
				(hide yes)
			)
		)
		(property "Current" "1A"
			(at 85.09 67.31 0)
			(effects
				(font
					(size 1.27 1.27)
					(thickness 0.15)
				)
				(justify left bottom)
				(hide yes)
			)
		)
		(pin "1"
		)
		(pin "2"
		)
		(instances
			(project "jetson-orin-baseboard"
				(path ""
					(reference "R17")
					(unit 1)
				)
			)
		)
	)
	(symbol
		(lib_name "R_0R_0402_7")
		(lib_id "antmicroResistors0402:R_0R_0402")
		(at 62.23 109.22 0)
		(unit 1)
		(exclude_from_sim no)
		(in_bom yes)
		(on_board yes)
		(dnp no)
		(property "Reference" "R15"
			(at 67.31 108.585 0)
			(effects
				(font
					(size 1.27 1.27)
				)
				(justify left bottom)
			)
		)
		(property "Value" "R_0R_0402"
			(at 82.55 121.92 0)
			(effects
				(font
					(size 1.27 1.27)
					(thickness 0.15)
				)
				(justify left bottom)
				(hide yes)
			)
		)
		(property "Footprint" "antmicro-footprints:R_0402_1005Metric"
			(at 82.55 124.46 0)
			(effects
				(font
					(size 1.27 1.27)
					(thickness 0.15)
				)
				(justify left bottom)
				(hide yes)
			)
		)
		(property "Datasheet" "https://industrial.panasonic.com/cdbs/www-data/pdf/RDA0000/AOA0000C301.pdf"
			(at 82.55 127 0)
			(effects
				(font
					(size 1.27 1.27)
					(thickness 0.15)
				)
				(justify left bottom)
				(hide yes)
			)
		)
		(property "Description" ""
			(at 62.23 109.22 0)
			(effects
				(font
					(size 1.27 1.27)
				)
				(hide yes)
			)
		)
		(property "Manufacturer" "Panasonic"
			(at 82.55 132.08 0)
			(effects
				(font
					(size 1.27 1.27)
					(thickness 0.15)
				)
				(justify left bottom)
				(hide yes)
			)
		)
		(property "MPN" "ERJ2GE0R00X"
			(at 82.55 129.54 0)
			(effects
				(font
					(size 1.27 1.27)
					(thickness 0.15)
				)
				(justify left bottom)
				(hide yes)
			)
		)
		(property "Val" "0R"
			(at 59.69 108.585 0)
			(effects
				(font
					(size 1.27 1.27)
					(thickness 0.15)
				)
				(justify left bottom)
			)
		)
		(property "License" "Apache-2.0"
			(at 82.55 134.62 0)
			(effects
				(font
					(size 1.27 1.27)
					(thickness 0.15)
				)
				(justify left bottom)
				(hide yes)
			)
		)
		(property "Author" "Antmicro"
			(at 82.55 137.16 0)
			(effects
				(font
					(size 1.27 1.27)
					(thickness 0.15)
				)
				(justify left bottom)
				(hide yes)
			)
		)
		(property "Tolerance" "~"
			(at 82.55 119.38 0)
			(effects
				(font
					(size 1.27 1.27)
				)
				(justify left bottom)
				(hide yes)
			)
		)
		(property "Current" "1A"
			(at 82.55 139.7 0)
			(effects
				(font
					(size 1.27 1.27)
					(thickness 0.15)
				)
				(justify left bottom)
				(hide yes)
			)
		)
		(pin "1"
		)
		(pin "2"
		)
		(instances
			(project "jetson-orin-baseboard"
				(path ""
					(reference "R15")
					(unit 1)
				)
			)
		)
	)
	(symbol
		(lib_id "antmicroLEDIndicationDiscrete:LED_G_0603_LTST-C190GKT")
		(at 241.3 240.03 90)
		(unit 1)
		(exclude_from_sim no)
		(in_bom yes)
		(on_board yes)
		(dnp no)
		(fields_autoplaced yes)
		(property "Reference" "D51"
			(at 243.205 236.22 90)
			(effects
				(font
					(size 1.27 1.27)
				)
				(justify right)
			)
		)
		(property "Value" "LED_G_0603_LTST-C190GKT"
			(at 248.92 217.17 0)
			(effects
				(font
					(size 1.27 1.27)
					(thickness 0.15)
				)
				(justify left bottom)
				(hide yes)
			)
		)
		(property "Footprint" "antmicro-footprints:LED_0603_1608Metric_G"
			(at 251.46 217.17 0)
			(effects
				(font
					(size 1.27 1.27)
					(thickness 0.15)
				)
				(justify left bottom)
				(hide yes)
			)
		)
		(property "Datasheet" "https://media.digikey.com/pdf/Data%20Sheets/Lite-On%20PDFs/LTST-C190GKT.pdf"
			(at 254 217.17 0)
			(effects
				(font
					(size 1.27 1.27)
					(thickness 0.15)
				)
				(justify left bottom)
				(hide yes)
			)
		)
		(property "Description" ""
			(at 241.3 240.03 0)
			(effects
				(font
					(size 1.27 1.27)
				)
				(hide yes)
			)
		)
		(property "MPN" "LTST-C190GKT"
			(at 256.54 217.17 0)
			(effects
				(font
					(size 1.27 1.27)
					(thickness 0.15)
				)
				(justify left bottom)
				(hide yes)
			)
		)
		(property "Manufacturer" "Lite-On"
			(at 259.08 217.17 0)
			(effects
				(font
					(size 1.27 1.27)
					(thickness 0.15)
				)
				(justify left bottom)
				(hide yes)
			)
		)
		(property "Author" "Antmicro"
			(at 261.62 217.17 0)
			(effects
				(font
					(size 1.27 1.27)
					(thickness 0.15)
				)
				(justify left bottom)
				(hide yes)
			)
		)
		(property "License" "Apache-2.0"
			(at 264.16 217.17 0)
			(effects
				(font
					(size 1.27 1.27)
					(thickness 0.15)
				)
				(justify left bottom)
				(hide yes)
			)
		)
		(property "Color" "Green"
			(at 243.205 238.76 90)
			(effects
				(font
					(size 1.27 1.27)
				)
				(justify right)
			)
		)
		(pin "1"
		)
		(pin "2"
		)
		(instances
			(project "jetson-orin-baseboard"
				(path ""
					(reference "D51")
					(unit 1)
				)
			)
		)
	)
	(symbol
		(lib_id "antmicroCapacitors0402:C_220n_0402")
		(at 157.48 177.8 0)
		(unit 1)
		(exclude_from_sim no)
		(in_bom yes)
		(on_board yes)
		(dnp no)
		(property "Reference" "C9"
			(at 161.29 177.165 0)
			(effects
				(font
					(size 1.27 1.27)
				)
				(justify left bottom)
			)
		)
		(property "Value" "C_220n_0402"
			(at 177.8 187.96 0)
			(effects
				(font
					(size 1.27 1.27)
					(thickness 0.15)
				)
				(justify left bottom)
				(hide yes)
			)
		)
		(property "Footprint" "antmicro-footprints:C_0402_1005Metric"
			(at 177.8 190.5 0)
			(effects
				(font
					(size 1.27 1.27)
					(thickness 0.15)
				)
				(justify left bottom)
				(hide yes)
			)
		)
		(property "Datasheet" "https://www.yageo.com/en/Chart/Download/pdf/CC0402KRX5R6BB224"
			(at 177.8 193.04 0)
			(effects
				(font
					(size 1.27 1.27)
					(thickness 0.15)
				)
				(justify left bottom)
				(hide yes)
			)
		)
		(property "Description" ""
			(at 157.48 177.8 0)
			(effects
				(font
					(size 1.27 1.27)
				)
				(hide yes)
			)
		)
		(property "Manufacturer" "YAGEO"
			(at 177.8 198.12 0)
			(effects
				(font
					(size 1.27 1.27)
					(thickness 0.15)
				)
				(justify left bottom)
				(hide yes)
			)
		)
		(property "MPN" "CC0402KRX5R6BB224"
			(at 177.8 195.58 0)
			(effects
				(font
					(size 1.27 1.27)
					(thickness 0.15)
				)
				(justify left bottom)
				(hide yes)
			)
		)
		(property "Val" "220n"
			(at 153.67 179.705 0)
			(effects
				(font
					(size 1.27 1.27)
					(thickness 0.15)
				)
				(justify left bottom)
			)
		)
		(property "License" "Apache-2.0"
			(at 177.8 200.66 0)
			(effects
				(font
					(size 1.27 1.27)
					(thickness 0.15)
				)
				(justify left bottom)
				(hide yes)
			)
		)
		(property "Author" "Antmicro"
			(at 177.8 203.2 0)
			(effects
				(font
					(size 1.27 1.27)
					(thickness 0.15)
				)
				(justify left bottom)
				(hide yes)
			)
		)
		(property "Voltage" ""
			(at 177.8 205.74 0)
			(effects
				(font
					(size 1.27 1.27)
				)
				(justify left bottom)
				(hide yes)
			)
		)
		(property "Dielectric" ""
			(at 177.8 208.28 0)
			(effects
				(font
					(size 1.27 1.27)
				)
				(justify left bottom)
				(hide yes)
			)
		)
		(pin "1"
		)
		(pin "2"
		)
		(instances
			(project "jetson-orin-baseboard"
				(path ""
					(reference "C9")
					(unit 1)
				)
			)
		)
	)
	(symbol
		(lib_name "GND_2")
		(lib_id "antmicropower:GND")
		(at 130.81 99.06 0)
		(unit 1)
		(exclude_from_sim no)
		(in_bom yes)
		(on_board yes)
		(dnp no)
		(property "Reference" "#PWR022"
			(at 130.81 105.41 0)
			(effects
				(font
					(size 1.27 1.27)
				)
				(justify left bottom)
				(hide yes)
			)
		)
		(property "Value" "GND"
			(at 130.81 102.87 0)
			(effects
				(font
					(size 1.27 1.27)
					(thickness 0.15)
				)
			)
		)
		(property "Footprint" ""
			(at 139.7 106.68 0)
			(effects
				(font
					(size 1.27 1.27)
					(thickness 0.15)
				)
				(justify left bottom)
				(hide yes)
			)
		)
		(property "Datasheet" ""
			(at 139.7 111.76 0)
			(effects
				(font
					(size 1.27 1.27)
					(thickness 0.15)
				)
				(justify left bottom)
				(hide yes)
			)
		)
		(property "Description" ""
			(at 130.81 99.06 0)
			(effects
				(font
					(size 1.27 1.27)
				)
				(hide yes)
			)
		)
		(property "Author" "Antmicro"
			(at 139.7 106.68 0)
			(effects
				(font
					(size 1.27 1.27)
					(thickness 0.15)
				)
				(justify left bottom)
				(hide yes)
			)
		)
		(property "License" "Apache-2.0"
			(at 139.7 109.22 0)
			(effects
				(font
					(size 1.27 1.27)
					(thickness 0.15)
				)
				(justify left bottom)
				(hide yes)
			)
		)
		(pin "1"
		)
		(instances
			(project "jetson-orin-baseboard"
				(path ""
					(reference "#PWR022")
					(unit 1)
				)
			)
		)
	)
	(symbol
		(lib_name "+3V3_1")
		(lib_id "antmicropower:+3V3")
		(at 40.64 153.67 0)
		(unit 1)
		(exclude_from_sim no)
		(in_bom yes)
		(on_board yes)
		(dnp no)
		(property "Reference" "#PWR044"
			(at 40.64 157.48 0)
			(effects
				(font
					(size 1.27 1.27)
				)
				(justify left bottom)
				(hide yes)
			)
		)
		(property "Value" "+3V3"
			(at 40.005 149.86 0)
			(effects
				(font
					(size 1.27 1.27)
					(thickness 0.15)
				)
			)
		)
		(property "Footprint" ""
			(at 55.88 161.29 0)
			(effects
				(font
					(size 1.27 1.27)
					(thickness 0.15)
				)
				(justify left bottom)
				(hide yes)
			)
		)
		(property "Datasheet" ""
			(at 55.88 163.83 0)
			(effects
				(font
					(size 1.27 1.27)
					(thickness 0.15)
				)
				(justify left bottom)
				(hide yes)
			)
		)
		(property "Description" ""
			(at 40.64 153.67 0)
			(effects
				(font
					(size 1.27 1.27)
				)
				(hide yes)
			)
		)
		(property "Author" "Antmicro"
			(at 55.88 156.21 0)
			(effects
				(font
					(size 1.27 1.27)
					(thickness 0.15)
				)
				(justify left bottom)
				(hide yes)
			)
		)
		(property "License" "Apache-2.0"
			(at 55.88 158.75 0)
			(effects
				(font
					(size 1.27 1.27)
					(thickness 0.15)
				)
				(justify left bottom)
				(hide yes)
			)
		)
		(pin "1"
		)
		(instances
			(project "jetson-orin-baseboard"
				(path ""
					(reference "#PWR044")
					(unit 1)
				)
			)
		)
	)
	(symbol
		(lib_id "antmicroTestPoints:TP_0.75mm_SMD")
		(at 264.16 198.12 0)
		(unit 1)
		(exclude_from_sim no)
		(in_bom no)
		(on_board yes)
		(dnp no)
		(property "Reference" "TP8"
			(at 267.97 198.755 0)
			(effects
				(font
					(size 1.27 1.27)
				)
				(justify left bottom)
			)
		)
		(property "Value" "TP_0.75mm_SMD"
			(at 274.32 201.93 0)
			(effects
				(font
					(size 1.27 1.27)
					(thickness 0.15)
				)
				(justify left bottom)
				(hide yes)
			)
		)
		(property "Footprint" "antmicro-footprints:TP_SMD_0.75mm"
			(at 274.32 204.47 0)
			(effects
				(font
					(size 1.27 1.27)
					(thickness 0.15)
				)
				(justify left bottom)
				(hide yes)
			)
		)
		(property "Datasheet" ""
			(at 281.94 210.82 0)
			(effects
				(font
					(size 1.27 1.27)
					(thickness 0.15)
				)
				(justify left bottom)
				(hide yes)
			)
		)
		(property "Description" ""
			(at 264.16 198.12 0)
			(effects
				(font
					(size 1.27 1.27)
				)
				(hide yes)
			)
		)
		(property "MPN" ""
			(at 274.955 209.55 0)
			(effects
				(font
					(size 1.27 1.27)
					(thickness 0.15)
				)
				(justify left bottom)
				(hide yes)
			)
		)
		(property "Manufacturer" ""
			(at 274.955 204.47 0)
			(effects
				(font
					(size 1.27 1.27)
					(thickness 0.15)
				)
				(justify left bottom)
				(hide yes)
			)
		)
		(property "Author" "Antmicro"
			(at 274.32 207.01 0)
			(effects
				(font
					(size 1.27 1.27)
					(thickness 0.15)
				)
				(justify left bottom)
				(hide yes)
			)
		)
		(property "License" "Apache-2.0"
			(at 274.32 209.55 0)
			(effects
				(font
					(size 1.27 1.27)
					(thickness 0.15)
				)
				(justify left bottom)
				(hide yes)
			)
		)
		(pin "1"
		)
		(instances
			(project "jetson-orin-baseboard"
				(path ""
					(reference "TP8")
					(unit 1)
				)
			)
		)
	)
	(symbol
		(lib_id "antmicropower:GND")
		(at 243.84 158.75 0)
		(unit 1)
		(exclude_from_sim no)
		(in_bom yes)
		(on_board yes)
		(dnp no)
		(property "Reference" "#PWR029"
			(at 243.84 165.1 0)
			(effects
				(font
					(size 1.27 1.27)
				)
				(justify left bottom)
				(hide yes)
			)
		)
		(property "Value" "GND"
			(at 241.935 162.56 0)
			(effects
				(font
					(size 1.27 1.27)
					(thickness 0.15)
				)
				(justify left)
			)
		)
		(property "Footprint" ""
			(at 252.73 166.37 0)
			(effects
				(font
					(size 1.27 1.27)
					(thickness 0.15)
				)
				(justify left bottom)
				(hide yes)
			)
		)
		(property "Datasheet" ""
			(at 252.73 171.45 0)
			(effects
				(font
					(size 1.27 1.27)
					(thickness 0.15)
				)
				(justify left bottom)
				(hide yes)
			)
		)
		(property "Description" ""
			(at 243.84 158.75 0)
			(effects
				(font
					(size 1.27 1.27)
				)
				(hide yes)
			)
		)
		(property "Author" "Antmicro"
			(at 252.73 166.37 0)
			(effects
				(font
					(size 1.27 1.27)
					(thickness 0.15)
				)
				(justify left bottom)
				(hide yes)
			)
		)
		(property "License" "Apache-2.0"
			(at 252.73 168.91 0)
			(effects
				(font
					(size 1.27 1.27)
					(thickness 0.15)
				)
				(justify left bottom)
				(hide yes)
			)
		)
		(pin "1"
		)
		(instances
			(project "jetson-orin-baseboard"
				(path ""
					(reference "#PWR029")
					(unit 1)
				)
			)
		)
	)
	(symbol
		(lib_id "antmicroModules:Mech_M2_2242_H2.5mm")
		(at 283.845 264.795 180)
		(unit 1)
		(exclude_from_sim no)
		(in_bom no)
		(on_board yes)
		(dnp yes)
		(property "Reference" "A2"
			(at 278.765 254 0)
			(effects
				(font
					(size 1.27 1.27)
					(thickness 0.15)
				)
			)
		)
		(property "Value" "Mech_M2_2242_H2.5mm"
			(at 278.765 256.54 0)
			(effects
				(font
					(size 1.27 1.27)
					(thickness 0.15)
				)
			)
		)
		(property "Footprint" "antmicro-footprints:Mech_M2_2242_H2.5mm"
			(at 258.445 259.715 0)
			(effects
				(font
					(size 1.27 1.27)
					(thickness 0.15)
				)
				(justify left bottom)
				(hide yes)
			)
		)
		(property "Datasheet" ""
			(at 258.445 257.175 0)
			(effects
				(font
					(size 1.27 1.27)
					(thickness 0.15)
				)
				(justify left bottom)
				(hide yes)
			)
		)
		(property "Description" ""
			(at 283.845 264.795 0)
			(effects
				(font
					(size 1.27 1.27)
				)
				(hide yes)
			)
		)
		(property "MPN" ""
			(at 283.845 264.795 0)
			(effects
				(font
					(size 1.27 1.27)
				)
			)
		)
		(property "Manufacturer" ""
			(at 283.845 264.795 0)
			(effects
				(font
					(size 1.27 1.27)
				)
				(hide yes)
			)
		)
		(property "Author" "Antmicro"
			(at 258.445 254.635 0)
			(effects
				(font
					(size 1.27 1.27)
					(thickness 0.15)
				)
				(justify left bottom)
				(hide yes)
			)
		)
		(property "License" "Apache-2.0"
			(at 258.445 252.095 0)
			(effects
				(font
					(size 1.27 1.27)
					(thickness 0.15)
				)
				(justify left bottom)
				(hide yes)
			)
		)
		(instances
			(project "jetson-orin-baseboard"
				(path ""
					(reference "A2")
					(unit 1)
				)
			)
		)
	)
	(symbol
		(lib_name "GND_8")
		(lib_id "antmicropower:GND")
		(at 397.51 123.19 0)
		(unit 1)
		(exclude_from_sim no)
		(in_bom yes)
		(on_board yes)
		(dnp no)
		(property "Reference" "#PWR043"
			(at 397.51 129.54 0)
			(effects
				(font
					(size 1.27 1.27)
				)
				(justify left bottom)
				(hide yes)
			)
		)
		(property "Value" "GND"
			(at 395.605 127 0)
			(effects
				(font
					(size 1.27 1.27)
					(thickness 0.15)
				)
				(justify left)
			)
		)
		(property "Footprint" ""
			(at 406.4 130.81 0)
			(effects
				(font
					(size 1.27 1.27)
					(thickness 0.15)
				)
				(justify left bottom)
				(hide yes)
			)
		)
		(property "Datasheet" ""
			(at 406.4 135.89 0)
			(effects
				(font
					(size 1.27 1.27)
					(thickness 0.15)
				)
				(justify left bottom)
				(hide yes)
			)
		)
		(property "Description" ""
			(at 397.51 123.19 0)
			(effects
				(font
					(size 1.27 1.27)
				)
				(hide yes)
			)
		)
		(property "Author" "Antmicro"
			(at 406.4 130.81 0)
			(effects
				(font
					(size 1.27 1.27)
					(thickness 0.15)
				)
				(justify left bottom)
				(hide yes)
			)
		)
		(property "License" "Apache-2.0"
			(at 406.4 133.35 0)
			(effects
				(font
					(size 1.27 1.27)
					(thickness 0.15)
				)
				(justify left bottom)
				(hide yes)
			)
		)
		(pin "1"
		)
		(instances
			(project "jetson-orin-baseboard"
				(path ""
					(reference "#PWR043")
					(unit 1)
				)
			)
		)
	)
)
